G04 ================== begin FILE IDENTIFICATION RECORD ==================*
G04 Layout Name:  E:/<user>/9332_F0TG_MB_C/brd/0417/9332_F0TG_MB_C_V02_0417_0820.brd*
G04 Film Name:    smb*
G04 File Format:  Gerber RS274X*
G04 File Origin:  Cadence Allegro 17.2-S081*
G04 Origin Date:  Wed Apr 19 14:49:57 2023*
G04 *
G04 Layer:  DRAWING FORMAT/TITLE_BLOCK_A*
G04 Layer:  DRAWING FORMAT/TITLE_BLOCK*
G04 Layer:  VIA CLASS/SOLDERMASK_BOTTOM*
G04 Layer:  PIN/SOLDERMASK_BOTTOM*
G04 Layer:  PACKAGE GEOMETRY/SOLDERMASK_BOTTOM*
G04 Layer:  MANUFACTURING/PHOTOPLOT_OUTLINE*
G04 Layer:  DRAWING FORMAT/TITLE_DATA_SMB*
G04 Layer:  BOARD GEOMETRY/SOLDERMASK_BOTTOM*
G04 *
G04 Offset:    (0.00 0.00)*
G04 Mirror:    No*
G04 Mode:      Positive*
G04 Rotation:  0*
G04 FullContactRelief:  No*
G04 UndefLineWidth:     6.00*
G04 ================== end FILE IDENTIFICATION RECORD ====================*
%FSLAX25Y25*MOIN*%
%IR0*IPPOS*OFA0.00000B0.00000*MIA0B0*SFA1.00000B1.00000*%
%ADD34O,.141X.072*%
%AMMACRO115*
21,1,.016,.0081,0.0,0.0,30.*%
%ADD115MACRO115*%
%ADD104O,.141X.068*%
%ADD12C,.03*%
%ADD99C,.04*%
%ADD82C,.022*%
%ADD94C,.05*%
%ADD33C,.024*%
%ADD120R,.0081X.016*%
%ADD114C,.052*%
%ADD96C,.034*%
%ADD70C,.07*%
%ADD52C,.061*%
%AMMACRO50*
21,1,.016,.0081,0.0,0.0,45.*%
%ADD50MACRO50*%
%ADD31C,.064*%
%ADD32C,.065*%
%ADD13R,.115X.099*%
%AMMACRO90*
4,1,8,.0445,-.0784,
.0445,.0784,
-.0445,.0784,
-.0445,.0216,
-.0165,.0216,
-.0165,-.0216,
-.0445,-.0216,
-.0445,-.0784,
.0445,-.0784,
0.0*
%
%ADD90MACRO90*%
%ADD81C,.066*%
%ADD39R,.099X.115*%
%ADD80C,.085*%
%ADD116R,.052X.052*%
%ADD73R,.07X.07*%
%ADD30C,.068*%
%ADD45C,.03417*%
%ADD126C,.0395*%
%ADD49R,.064X.064*%
%ADD42C,.02717*%
%ADD35R,.065X.065*%
%ADD125C,.0785*%
%ADD113R,.068X.068*%
%AMMACRO59*
4,1,28,.00086,.01327,
-.000066,.013712,
-.001055,.013988,
-.002076,.014088,
-.003099,.01401,
-.004093,.013755,
-.005027,.013331,
-.005874,.012752,
-.006607,.012034,
-.007205,.0112,
-.00724,.01114,
-.01099,.00464,
-.00895,.00346,
-.01416,-.00557,
.00225,-.01505,
.00747,-.00602,
.00951,-.0072,
.01327,-.0007,
.013703,.000231,
.013969,.001222,
.014059,.002244,
.013971,.003266,
.013706,.004257,
.013273,.005188,
.012685,.006029,
.01196,.006755,
.01112,.007344,
.01106,.00738,
.00086,.01327,
0.0*
%
%ADD59MACRO59*%
%ADD43R,.03417X.03417*%
%AMMACRO91*
4,1,8,.0034,.0082,
-.0034,.0082,
-.0082,.0034,
-.0082,-.00341,
-.00341,-.0082,
.0034,-.0082,
.0082,-.0034,
.0082,.0034,
.0034,.0082,
0.0*
%
%ADD91MACRO91*%
%AMMACRO19*
4,1,28,-.00589,.01192,
-.006913,.011842,
-.007907,.011587,
-.008842,.011163,
-.009688,.010584,
-.010422,.009866,
-.011019,.009032,
-.011463,.008107,
-.011739,.007119,
-.01184,.006097,
-.01184,.00603,
-.01184,-.00148,
-.00948,-.00148,
-.00948,-.01191,
.00948,-.01191,
.00948,-.00148,
.01184,-.00148,
.01184,.00603,
.011751,.007052,
.011486,.008044,
.011053,.008974,
.010465,.009815,
.00974,.010541,
.0089,.01113,
.00797,.011564,
.006979,.01183,
.005957,.01192,
.00589,.01192,
-.00589,.01192,
0.0*
%
%ADD19MACRO19*%
%ADD100C,.06974*%
%AMMACRO89*
4,1,8,.0082,-.0034,
.0082,.0034,
.0034,.0082,
-.00341,.0082,
-.0082,.00341,
-.0082,-.0034,
-.0034,-.0082,
.0034,-.0082,
.0082,-.0034,
0.0*
%
%ADD89MACRO89*%
%ADD41C,.03968*%
%AMMACRO21*
4,1,28,.01192,.00589,
.011842,.006913,
.011587,.007907,
.011163,.008842,
.010584,.009688,
.009866,.010422,
.009032,.011019,
.008107,.011463,
.007119,.011739,
.006097,.01184,
.00603,.01184,
-.00148,.01184,
-.00148,.00948,
-.01191,.00948,
-.01191,-.00948,
-.00148,-.00948,
-.00148,-.01184,
.00603,-.01184,
.007052,-.011751,
.008044,-.011486,
.008974,-.011053,
.009815,-.010465,
.010541,-.00974,
.01113,-.0089,
.011564,-.00797,
.01183,-.006979,
.01192,-.005957,
.01192,-.00589,
.01192,.00589,
0.0*
%
%ADD21MACRO21*%
%AMMACRO58*
4,1,28,-.00085,-.01326,
.000075,-.013704,
.001063,-.01398,
.002084,-.01408,
.003107,-.014001,
.004101,-.013745,
.005035,-.013321,
.005882,-.012741,
.006615,-.012023,
.007212,-.011189,
.00724,-.01113,
.011,-.00463,
.00895,-.00345,
.01417,.00558,
-.00225,.01506,
-.00746,.00603,
-.00951,.00721,
-.01326,.00071,
-.013696,-.000219,
-.013963,-.001209,
-.014054,-.002231,
-.013966,-.003253,
-.013702,-.004245,
-.01327,-.005176,
-.012683,-.006017,
-.011958,-.006744,
-.011119,-.007333,
-.01106,-.00736,
-.00085,-.01326,
0.0*
%
%ADD58MACRO58*%
%AMMACRO18*
4,1,28,.0059,-.01191,
.006923,-.01183,
.007916,-.011573,
.00885,-.011148,
.009696,-.010567,
.010428,-.009849,
.011024,-.009013,
.011466,-.008088,
.011741,-.007099,
.01184,-.006078,
.01184,-.00602,
.01184,.00149,
.00948,.00149,
.00948,.01192,
-.00948,.01192,
-.00948,.00149,
-.01184,.00149,
-.01184,-.00602,
-.011751,-.007042,
-.011486,-.008033,
-.011053,-.008964,
-.010465,-.009805,
-.00974,-.010531,
-.0089,-.01112,
-.007971,-.011554,
-.00698,-.01182,
-.005958,-.01191,
-.0059,-.01191,
.0059,-.01191,
0.0*
%
%ADD18MACRO18*%
%AMMACRO20*
4,1,28,-.01191,-.0059,
-.01183,-.006923,
-.011573,-.007916,
-.011148,-.00885,
-.010567,-.009696,
-.009849,-.010428,
-.009013,-.011024,
-.008088,-.011466,
-.007099,-.011741,
-.006078,-.01184,
-.00602,-.01184,
.00149,-.01184,
.00149,-.00948,
.01192,-.00948,
.01192,.00948,
.00149,.00948,
.00149,.01184,
-.00602,.01184,
-.007042,.011751,
-.008033,.011486,
-.008964,.011053,
-.009805,.010465,
-.010531,.00974,
-.01112,.0089,
-.011554,.007971,
-.01182,.00698,
-.01191,.005958,
-.01191,.0059,
-.01191,-.0059,
0.0*
%
%ADD20MACRO20*%
%ADD111R,.06974X.06974*%
%ADD51R,.03X.011*%
%ADD53R,.011X.03*%
%ADD83R,.024X.02*%
%ADD107R,.021X.05*%
%ADD40R,.024X.021*%
%ADD105O,.275X.22*%
%ADD68R,.024X.022*%
%ADD62R,.021X.024*%
%ADD110R,.022X.024*%
%ADD76R,.025X.014*%
%ADD28R,.011X.036*%
%ADD27R,.028X.011*%
%ADD121R,.04X.036*%
%ADD79R,.014X.025*%
%ADD56R,.024X.016*%
%ADD108R,.014X.026*%
%ADD98R,.021X.028*%
%ADD85R,.036X.04*%
%ADD75R,.025X.016*%
%ADD48R,.036X.032*%
%ADD117R,.044X.06*%
%ADD84R,.06X.018*%
%ADD78R,.016X.025*%
%ADD23R,.032X.036*%
%ADD124C,.142*%
%AMMACRO118*
21,1,.016,.0081,0.0,0.0,135.*%
%ADD118MACRO118*%
%ADD106R,.028X.05*%
%ADD71R,.063X.052*%
%AMMACRO69*
21,1,.016,.0081,0.0,0.0,144.*%
%ADD69MACRO69*%
%ADD67C,.26*%
%ADD38R,.019X.016*%
%ADD24R,.054X.044*%
%ADD103C,.162*%
%ADD93R,.063X.018*%
%ADD44O,.319X.256*%
%ADD37R,.016X.019*%
%ADD36C,.414*%
%ADD29R,.044X.054*%
%ADD86R,.029X.052*%
%ADD77R,.029X.017*%
%ADD15C,.145*%
%ADD11C,.118*%
%ADD123R,.057X.026*%
%ADD102R,.067X.016*%
%ADD74R,.017X.029*%
%AMMACRO55*
4,1,8,-.0445,.0784,
-.0445,-.0784,
.0445,-.0784,
.0445,-.0216,
.0165,-.0216,
.0165,.0216,
.0445,.0216,
.0445,.0784,
-.0445,.0784,
0.0*
%
%ADD55MACRO55*%
%ADD122R,.067X.044*%
%ADD119R,.054X.039*%
%ADD97C,.237*%
%ADD92R,.028X.046*%
%ADD72R,.044X.075*%
%ADD101R,.067X.018*%
%ADD46C,.319*%
%ADD112R,.067X.019*%
%ADD14C,.248*%
%ADD95C,.295*%
%ADD61R,.058X.048*%
%ADD47C,.178*%
%ADD22R,.048X.058*%
%AMMACRO66*
4,1,28,-.01106,.00738,
-.011906,.0068,
-.01264,.006082,
-.013238,.005248,
-.013682,.004323,
-.013958,.003335,
-.014059,.002314,
-.013981,.001291,
-.013726,.000297,
-.013303,-.000638,
-.01327,-.0007,
-.00951,-.0072,
-.00747,-.00602,
-.00225,-.01505,
.01416,-.00557,
.00895,.00346,
.01099,.00464,
.00724,.01114,
.006652,.011981,
.005928,.012707,
.005088,.013297,
.004158,.013732,
.003167,.013998,
.002145,.014089,
.001123,.014,
.000132,.013736,
-.000799,.013303,
-.00086,.01327,
-.01106,.00738,
0.0*
%
%ADD66MACRO66*%
%AMMACRO57*
4,1,28,.01106,-.00738,
.011906,-.0068,
.01264,-.006082,
.013238,-.005248,
.013682,-.004323,
.013958,-.003335,
.014059,-.002314,
.013981,-.001291,
.013726,-.000297,
.013303,.000638,
.01327,.0007,
.00951,.0072,
.00747,.00602,
.00225,.01505,
-.01416,.00557,
-.00895,-.00346,
-.01099,-.00464,
-.00724,-.01114,
-.006652,-.011981,
-.005928,-.012707,
-.005088,-.013297,
-.004158,-.013732,
-.003167,-.013998,
-.002145,-.014089,
-.001123,-.014,
-.000132,-.013736,
.000799,-.013303,
.00086,-.01327,
.01106,-.00738,
0.0*
%
%ADD57MACRO57*%
%ADD10C,.398*%
%AMMACRO64*
4,1,28,-.00086,-.01327,
.000066,-.013712,
.001055,-.013988,
.002076,-.014088,
.003099,-.01401,
.004093,-.013755,
.005027,-.013331,
.005874,-.012752,
.006607,-.012034,
.007205,-.0112,
.00724,-.01114,
.01099,-.00464,
.00895,-.00346,
.01416,.00557,
-.00225,.01505,
-.00747,.00602,
-.00951,.0072,
-.01327,.0007,
-.013703,-.000231,
-.013969,-.001222,
-.014059,-.002244,
-.013971,-.003266,
-.013706,-.004257,
-.013273,-.005188,
-.012685,-.006029,
-.01196,-.006755,
-.01112,-.007344,
-.01106,-.00738,
-.00086,-.01327,
0.0*
%
%ADD64MACRO64*%
%AMMACRO109*
4,1,46,.03153,-.02165,
.03153,.02165,
.031381,.023365,
.030936,.025028,
.030209,.026589,
.029222,.027999,
.028005,.029217,
.026595,.030205,
.025035,.030933,
.023372,.031379,
.021657,.03153,
.02165,.03153,
-.02396,.03153,
-.023697,.030533,
-.02361,.029505,
-.023704,.028478,
-.023974,.027483,
-.024413,.02655,
-.025007,.025708,
-.025739,.024981,
-.026586,.024392,
-.027522,.02396,
-.028519,.023696,
-.02953,.02361,
-.03153,.02361,
-.03153,-.02165,
-.031381,-.023365,
-.030936,-.025028,
-.030209,-.026589,
-.029222,-.027999,
-.028005,-.029217,
-.026595,-.030205,
-.025035,-.030933,
-.023372,-.031379,
-.021657,-.03153,
-.02165,-.03153,
.02165,-.03153,
.023365,-.031381,
.025028,-.030936,
.026589,-.030209,
.027999,-.029222,
.029217,-.028005,
.030205,-.026595,
.030933,-.025035,
.031379,-.023372,
.03153,-.021657,
.03153,-.02165,
0.0*
%
%ADD109MACRO109*%
%ADD54R,.178X.178*%
%AMMACRO88*
4,1,8,-.0034,-.0082,
.0034,-.0082,
.0082,-.0034,
.0082,.00341,
.00341,.0082,
-.0034,.0082,
-.0082,.0034,
-.0082,-.0034,
-.0034,-.0082,
0.0*
%
%ADD88MACRO88*%
%AMMACRO87*
4,1,8,-.0082,.0034,
-.0082,-.0034,
-.0034,-.0082,
.00341,-.0082,
.0082,-.00341,
.0082,.0034,
.0034,.0082,
-.0034,.0082,
-.0082,.0034,
0.0*
%
%ADD87MACRO87*%
%AMMACRO65*
4,1,28,.01106,-.00736,
.011909,-.006785,
.012641,-.006066,
.013238,-.005231,
.01368,-.004305,
.013955,-.003317,
.014054,-.002296,
.013974,-.001273,
.013718,-.000279,
.013293,.000655,
.01326,.00071,
.00951,.00721,
.00746,.00603,
.00225,.01506,
-.01417,.00558,
-.00895,-.00345,
-.011,-.00463,
-.00724,-.01113,
-.006657,-.011973,
-.005932,-.0127,
-.005092,-.013289,
-.004162,-.013723,
-.003171,-.01399,
-.002149,-.01408,
-.001127,-.013991,
-.000136,-.013727,
.000795,-.013294,
.00085,-.01326,
.01106,-.00736,
0.0*
%
%ADD65MACRO65*%
%AMMACRO60*
4,1,28,-.01106,.00736,
-.011909,.006785,
-.012641,.006066,
-.013238,.005231,
-.01368,.004305,
-.013955,.003317,
-.014054,.002296,
-.013974,.001273,
-.013718,.000279,
-.013293,-.000655,
-.01326,-.00071,
-.00951,-.00721,
-.00746,-.00603,
-.00225,-.01506,
.01417,-.00558,
.00895,.00345,
.011,.00463,
.00724,.01113,
.006657,.011973,
.005932,.0127,
.005092,.013289,
.004162,.013723,
.003171,.01399,
.002149,.01408,
.001127,.013991,
.000136,.013727,
-.000795,.013294,
-.00085,.01326,
-.01106,.00736,
0.0*
%
%ADD60MACRO60*%
%AMMACRO26*
4,1,28,-.01192,-.00589,
-.011842,-.006913,
-.011587,-.007907,
-.011163,-.008842,
-.010584,-.009688,
-.009866,-.010422,
-.009032,-.011019,
-.008107,-.011463,
-.007119,-.011739,
-.006097,-.01184,
-.00603,-.01184,
.00148,-.01184,
.00148,-.00948,
.01191,-.00948,
.01191,.00948,
.00148,.00948,
.00148,.01184,
-.00603,.01184,
-.007052,.011751,
-.008044,.011486,
-.008974,.011053,
-.009815,.010465,
-.010541,.00974,
-.01113,.0089,
-.011564,.00797,
-.01183,.006979,
-.01192,.005957,
-.01192,.00589,
-.01192,-.00589,
0.0*
%
%ADD26MACRO26*%
%AMMACRO17*
4,1,28,.00589,-.01192,
.006913,-.011842,
.007907,-.011587,
.008842,-.011163,
.009688,-.010584,
.010422,-.009866,
.011019,-.009032,
.011463,-.008107,
.011739,-.007119,
.01184,-.006097,
.01184,-.00603,
.01184,.00148,
.00948,.00148,
.00948,.01191,
-.00948,.01191,
-.00948,.00148,
-.01184,.00148,
-.01184,-.00603,
-.011751,-.007052,
-.011486,-.008044,
-.011053,-.008974,
-.010465,-.009815,
-.00974,-.010541,
-.0089,-.01113,
-.00797,-.011564,
-.006979,-.01183,
-.005957,-.01192,
-.00589,-.01192,
.00589,-.01192,
0.0*
%
%ADD17MACRO17*%
%AMMACRO63*
4,1,28,.00085,.01326,
-.000075,.013704,
-.001063,.01398,
-.002084,.01408,
-.003107,.014001,
-.004101,.013745,
-.005035,.013321,
-.005882,.012741,
-.006615,.012023,
-.007212,.011189,
-.00724,.01113,
-.011,.00463,
-.00895,.00345,
-.01417,-.00558,
.00225,-.01506,
.00746,-.00603,
.00951,-.00721,
.01326,-.00071,
.013696,.000219,
.013963,.001209,
.014054,.002231,
.013966,.003253,
.013702,.004245,
.01327,.005176,
.012683,.006017,
.011958,.006744,
.011119,.007333,
.01106,.00736,
.00085,.01326,
0.0*
%
%ADD63MACRO63*%
%AMMACRO25*
4,1,28,.01191,.0059,
.01183,.006923,
.011573,.007916,
.011148,.00885,
.010567,.009696,
.009849,.010428,
.009013,.011024,
.008088,.011466,
.007099,.011741,
.006078,.01184,
.00602,.01184,
-.00149,.01184,
-.00149,.00948,
-.01192,.00948,
-.01192,-.00948,
-.00149,-.00948,
-.00149,-.01184,
.00602,-.01184,
.007042,-.011751,
.008033,-.011486,
.008964,-.011053,
.009805,-.010465,
.010531,-.00974,
.01112,-.0089,
.011554,-.007971,
.01182,-.00698,
.01191,-.005958,
.01191,-.0059,
.01191,.0059,
0.0*
%
%ADD25MACRO25*%
%AMMACRO16*
4,1,28,-.0059,.01191,
-.006923,.01183,
-.007916,.011573,
-.00885,.011148,
-.009696,.010567,
-.010428,.009849,
-.011024,.009013,
-.011466,.008088,
-.011741,.007099,
-.01184,.006078,
-.01184,.00602,
-.01184,-.00149,
-.00948,-.00149,
-.00948,-.01192,
.00948,-.01192,
.00948,-.00149,
.01184,-.00149,
.01184,.00602,
.011751,.007042,
.011486,.008033,
.011053,.008964,
.010465,.009805,
.00974,.010531,
.0089,.01112,
.007971,.011554,
.00698,.01182,
.005958,.01191,
.0059,.01191,
-.0059,.01191,
0.0*
%
%ADD16MACRO16*%
%ADD127C,.02*%
%ADD128C,.006*%
%ADD129C,.2542*%
%ADD130C,.1582*%
G75*
%LPD*%
G75*
G36*
G01X26609Y139746D02*
G03I-5900J0D01*
G37*
G36*
G01X29463Y1590338D02*
G03I-5900J0D01*
G37*
G36*
G01X56058Y124181D02*
G02X65762Y113808I4852J-5187D01*
G01X61162Y109505D01*
G02X51458Y119878I-4852J5186D01*
G01X56058Y124181D01*
G37*
G36*
G01X138618Y605378D02*
G02I-20685J0D01*
G37*
G36*
G01X147929Y1482244D02*
G02I-9858J0D01*
G37*
G36*
G01X173520Y1593661D02*
G02I-9858J0D01*
G37*
G36*
G01X198098Y260083D02*
G02X156728I-20685J0D01*
G01Y294335D01*
G02X198098I20685J0D01*
G01Y260083D01*
G37*
G36*
G01X288893Y1019214D02*
G02I-13980J0D01*
G37*
G36*
G01X334168Y838505D02*
G02I-13979J0D01*
G37*
G36*
G01Y1199923D02*
G02I-13979J0D01*
G37*
G36*
G01X415159Y412106D02*
G03I-5900J0D01*
G37*
G36*
G01X575113Y838505D02*
G02I-13980J0D01*
G37*
G36*
G01Y1199923D02*
G02I-13980J0D01*
G37*
G36*
G01X620389Y1019214D02*
G02I-13980J0D01*
G37*
G36*
G01X683087Y1593661D02*
G02I-9858J0D01*
G37*
G36*
G01X724870Y260110D02*
G02X683500I-20685J0D01*
G01Y294362D01*
G02X724870I20685J0D01*
G01Y260110D01*
G37*
G36*
G01X708677Y1482244D02*
G02I-9858J0D01*
G37*
G36*
G01X784287Y605413D02*
G02I-20685J0D01*
G37*
G36*
G01X825575Y204724D02*
G02I-19885J0D01*
G37*
G36*
G01X857240Y1420331D02*
G02I-16000J0D01*
G37*
G36*
G01X870525Y1368522D02*
G03I-5900J0D01*
G37*
G36*
G01X948625Y321654D02*
G02I-19885J0D01*
G37*
G36*
G01X930909Y1014595D02*
G03I-5900J0D01*
G37*
G36*
G01X1032240Y1420331D02*
G02I-16000J0D01*
G37*
G36*
G01X1077544Y204724D02*
G02I-19885J0D01*
G37*
G36*
G01X1114760Y605378D02*
G02I-20685J0D01*
G37*
G36*
G01X1094563Y299646D02*
G03I-5900J0D01*
G37*
G36*
G01X1174240Y260083D02*
G02X1132870I-20685J0D01*
G01Y294335D01*
G02X1174240I20685J0D01*
G01Y260083D01*
G37*
G36*
G01X1155803Y1515236D02*
G02I-9858J0D01*
G37*
G36*
G01X1181394Y1626654D02*
G02I-9858J0D01*
G37*
G36*
G01X1265035Y1019213D02*
G02I-13980J0D01*
G37*
G36*
G01X1310310Y838504D02*
G02I-13979J0D01*
G37*
G36*
G01Y1199922D02*
G02I-13979J0D01*
G37*
G36*
G01X1495857Y1403002D02*
G03I-5900J0D01*
G37*
G36*
G01X1551255Y838504D02*
G02I-13980J0D01*
G37*
G36*
G01Y1199922D02*
G02I-13980J0D01*
G37*
G36*
G01X1574692Y178239D02*
G03I-5900J0D01*
G37*
G36*
G01X1596531Y1019213D02*
G02I-13980J0D01*
G37*
G36*
G01X1701012Y260110D02*
G02X1659642I-20685J0D01*
G01Y294362D01*
G02X1701012I20685J0D01*
G01Y260110D01*
G37*
G36*
G01X1690961Y1626654D02*
G02I-9858J0D01*
G37*
G36*
G01X1716551Y1515236D02*
G02I-9858J0D01*
G37*
G36*
G01X1710830Y1649379D02*
G03I-5900J0D01*
G37*
G36*
G01X1760429Y605413D02*
G02I-20685J0D01*
G37*
G36*
G01X1776979Y1714960D02*
G02I-10050J0D01*
G37*
G36*
G01X1837024Y127165D02*
G02X1822819I-7103J0D01*
G01Y133465D01*
G02X1837024I7103J0D01*
G01Y127165D01*
G37*
%LPC*%
G75*
G54D129*
X805690Y204724D03*
X1057659D03*
G54D130*
X1766929Y1714960D03*
%LPD*%
G75*
G54D100*
X828780Y1684890D03*
X818780D03*
X828780Y1694890D03*
X818780D03*
X828780Y1704890D03*
X818780D03*
X828780Y1714890D03*
X818780D03*
X853780Y1684890D03*
Y1694890D03*
Y1704890D03*
Y1714890D03*
X863780Y1684890D03*
Y1694890D03*
Y1704890D03*
Y1714890D03*
X888780Y1684890D03*
Y1694890D03*
Y1704890D03*
Y1714890D03*
X898780Y1684890D03*
Y1694890D03*
Y1704890D03*
Y1714890D03*
X918780Y1684890D03*
Y1694890D03*
Y1704890D03*
Y1714890D03*
X928780Y1684890D03*
Y1694890D03*
Y1704890D03*
Y1714890D03*
X938780Y1684890D03*
Y1694890D03*
Y1704890D03*
X958780Y1684890D03*
Y1694890D03*
Y1704890D03*
Y1714890D03*
X968780Y1684890D03*
Y1694890D03*
Y1704890D03*
Y1714890D03*
X993780Y1684890D03*
Y1694890D03*
Y1704890D03*
Y1714890D03*
X1003780Y1684890D03*
Y1694890D03*
Y1704890D03*
Y1714890D03*
X1028780Y1684890D03*
X1038780D03*
X1028780Y1694890D03*
X1038780D03*
X1028780Y1704890D03*
Y1714890D03*
X1038780Y1704890D03*
Y1714890D03*
G54D101*
X864599Y1281729D03*
Y1279170D03*
Y1276611D03*
Y1294525D03*
Y1291966D03*
Y1289407D03*
Y1286848D03*
Y1284288D03*
X886647Y1276611D03*
Y1279170D03*
Y1281729D03*
Y1284288D03*
Y1286848D03*
Y1289407D03*
Y1291966D03*
Y1294525D03*
G54D110*
X914623Y1266833D03*
X911473D03*
X908323D03*
X911473D03*
X914737Y1271025D03*
X911587D03*
X908437D03*
X911587D03*
X908159Y1283775D03*
X911309D03*
X914459D03*
X911309D03*
X908199Y1279451D03*
X911349D03*
X914499D03*
X911349D03*
X908168Y1275251D03*
X911318D03*
X914468D03*
X911318D03*
X907988Y1296713D03*
X911138D03*
X914288D03*
X911138D03*
X908008Y1292330D03*
X911158D03*
X914308D03*
X911158D03*
X908075Y1288235D03*
X911225D03*
X914375D03*
X911225D03*
X923962Y839601D03*
X920812D03*
X924075Y847191D03*
X920925D03*
X923962Y839601D03*
X927112D03*
X924075Y847191D03*
X927225D03*
X918425Y893000D03*
X921575D03*
X924725D03*
X921575D03*
X918425Y898000D03*
X921575D03*
X924725D03*
X921575D03*
X930775Y982500D03*
Y977500D03*
X933925Y982500D03*
Y977500D03*
Y982500D03*
X937075D03*
X933925Y977500D03*
X937075D03*
X1571182Y1278788D03*
X1568032D03*
X1564882D03*
X1568032D03*
X1586282Y1275168D03*
X1592582D03*
X1589432D03*
D03*
G54D102*
X872087Y1312091D03*
Y1327446D03*
Y1324886D03*
Y1322327D03*
Y1319768D03*
Y1317209D03*
Y1314650D03*
Y1340241D03*
Y1337682D03*
Y1335123D03*
Y1332564D03*
Y1330005D03*
X894135Y1312091D03*
Y1314650D03*
Y1317209D03*
Y1319768D03*
Y1322327D03*
Y1324886D03*
Y1327446D03*
Y1330005D03*
Y1332564D03*
Y1335123D03*
Y1337682D03*
Y1340241D03*
X962459Y1312091D03*
Y1327446D03*
Y1324886D03*
Y1322327D03*
Y1319768D03*
Y1317209D03*
Y1314650D03*
Y1340241D03*
Y1337682D03*
Y1335123D03*
Y1332564D03*
Y1330005D03*
X984507Y1312091D03*
Y1314650D03*
Y1317209D03*
Y1319768D03*
Y1322327D03*
Y1324886D03*
Y1327446D03*
Y1330005D03*
Y1332564D03*
Y1335123D03*
Y1337682D03*
Y1340241D03*
G54D111*
X938780Y1714890D03*
G54D120*
X1504000Y812640D03*
G54D10*
X27559Y87795D03*
X40708Y631889D03*
Y1368908D03*
X51180Y1714961D03*
X373622Y87795D03*
X395671Y1714960D03*
X661024Y631890D03*
X707677Y1714960D03*
X800787Y87795D03*
X931693Y757874D03*
X931692Y1072835D03*
X931693Y1387795D03*
X1045866Y87795D03*
X1155709Y1714961D03*
X1271260Y631890D03*
X1461806Y1714961D03*
X1499606Y87795D03*
X1806298Y1714961D03*
X1829921Y87795D03*
X1816772Y631889D03*
Y1368897D03*
G54D112*
X973423Y1283193D03*
Y1280693D03*
Y1278193D03*
Y1275693D03*
Y1273193D03*
Y1290693D03*
Y1288193D03*
Y1285693D03*
X994329Y1273193D03*
Y1275693D03*
Y1278193D03*
Y1280693D03*
Y1283193D03*
Y1285693D03*
Y1288193D03*
Y1290693D03*
G54D103*
X900197Y175177D03*
X944685Y155197D03*
G54D121*
X1551887Y610299D03*
Y602819D03*
X1559761Y606559D03*
G54D122*
X1567913Y593271D03*
Y605869D03*
X1576213Y593271D03*
X1584513D03*
X1576213Y605869D03*
X1584513D03*
X1592813Y593271D03*
Y605869D03*
G54D11*
X20709Y139746D03*
X23563Y1590338D03*
X409259Y412106D03*
X864625Y1368522D03*
X925009Y1014595D03*
X1088663Y299646D03*
X1489957Y1403002D03*
X1568792Y178239D03*
X1704930Y1649379D03*
G54D20*
X30771Y441130D03*
Y445519D03*
X38149Y1603396D03*
Y1623196D03*
X62329Y388462D03*
X62327Y393079D03*
X57738Y528205D03*
X57943Y1654387D03*
X80875Y763766D03*
X78516Y1444500D03*
Y1448500D03*
X79183Y1629905D03*
X110576Y763766D03*
X100576D03*
X127016Y1436500D03*
X140408Y763700D03*
X130277Y763766D03*
X137516Y1425000D03*
X134516Y1429000D03*
X170078Y763666D03*
X159916Y763766D03*
X199778D03*
X189678D03*
X200939Y1658170D03*
X200597Y1664479D03*
X204675Y751266D03*
X207774Y1658192D03*
X207546Y1664479D03*
X219279Y763766D03*
X227631Y960966D03*
X232379Y763766D03*
X255916Y58400D03*
Y62400D03*
X247313Y111743D03*
X263087Y775410D03*
Y784788D03*
Y780588D03*
X274787Y793988D03*
Y797988D03*
X288657Y37420D03*
X336516Y582500D03*
Y578500D03*
X345673Y591335D03*
Y586415D03*
X353673Y558415D03*
Y562415D03*
Y570415D03*
Y574415D03*
X357854Y1198131D03*
X370309Y239452D03*
X366316Y544000D03*
Y548000D03*
X370447Y1192148D03*
X370516Y1187862D03*
Y1195862D03*
X370407Y1207538D03*
X386726Y1003766D03*
X386287Y1037488D03*
X393287Y1043488D03*
X386287Y1031288D03*
Y1043488D03*
X393287Y1031288D03*
Y1037488D03*
X386132Y1049766D03*
X388132Y1053266D03*
X393675Y1056766D03*
X391675Y1060266D03*
X382733Y1670046D03*
Y1673985D03*
X397673Y573415D03*
X401673Y577415D03*
X409175Y997766D03*
Y991266D03*
X399675Y1007266D03*
Y1028266D03*
X402675Y1040766D03*
X410175D03*
X399675Y1034266D03*
X395675Y1047266D03*
X402675Y1053266D03*
X410175D03*
X403175Y1060266D03*
X401175Y1056766D03*
X395675Y1053266D03*
X408675Y1056766D03*
X410175Y1047266D03*
X403175D03*
X410016Y1672500D03*
X412787Y966488D03*
X412675Y978266D03*
X424287Y985266D03*
X416675Y991266D03*
X424175D03*
X416675Y997766D03*
X424175D03*
X417675Y1040766D03*
X425175D03*
X415682Y1032304D03*
X417675Y1053266D03*
X416175Y1056766D03*
X425175Y1053266D03*
X423175Y1056766D03*
X414175Y1060266D03*
X425175Y1047266D03*
X417675D03*
X414287Y1071988D03*
X424336Y1615168D03*
X414016Y1653500D03*
X425687Y970088D03*
X431175Y985266D03*
Y997766D03*
Y991266D03*
X439675Y1042766D03*
Y1038766D03*
X430675Y1056766D03*
X432675Y1053266D03*
X432175Y1047266D03*
X427287Y1068488D03*
X426993Y1608370D03*
X436016Y1626000D03*
X439016Y1630000D03*
X446709Y106490D03*
Y102490D03*
X447675Y981766D03*
X446175Y985266D03*
X455175Y981766D03*
X453675Y997766D03*
Y991266D03*
X455175Y987766D03*
X446175Y997766D03*
Y991266D03*
X454675Y1040766D03*
X447465Y1053266D03*
X449175Y1056766D03*
X454946Y1053266D03*
X447175Y1047266D03*
X454675D03*
X457287Y966488D03*
X470175Y981766D03*
X457175Y978266D03*
X462675Y981766D03*
X460675Y991266D03*
Y997766D03*
X462675Y987766D03*
X470175D03*
X468175Y997766D03*
Y991266D03*
X462672Y1013604D03*
Y1009864D03*
Y1006123D03*
Y1017344D03*
Y1024824D03*
Y1028564D03*
Y1021084D03*
Y1032304D03*
X462175Y1040766D03*
X469675D03*
X462175Y1047266D03*
X469675D03*
X456675Y1056766D03*
X462426Y1053266D03*
X464175Y1056766D03*
X469675Y1053145D03*
X458675Y1060266D03*
X458287Y1071988D03*
X474934Y285693D03*
X479551Y966489D03*
X477675Y981766D03*
X479251Y978266D03*
X477675Y1000766D03*
Y994266D03*
Y987766D03*
X477594Y1015474D03*
X477675Y1007266D03*
X480675Y1027745D03*
X477594Y1019017D03*
Y1022560D03*
X484175Y1040766D03*
X478613Y1037266D03*
X482223Y1031245D03*
X476675Y1040766D03*
X484175Y1047266D03*
X477175D03*
X484175Y1053145D03*
X471175Y1056766D03*
X476675Y1053145D03*
X478675Y1056766D03*
X480787Y1071988D03*
X496058Y143545D03*
Y147545D03*
Y138598D03*
X490551Y978266D03*
X485175Y981766D03*
X492175D03*
Y994266D03*
X485175Y1000766D03*
X492175D03*
Y987766D03*
X485175Y994266D03*
Y987766D03*
Y1007266D03*
Y1015474D03*
X492175D03*
Y1007266D03*
X488175Y1027745D03*
X492175Y1022560D03*
X485175Y1019017D03*
Y1022560D03*
X492175Y1019017D03*
X488175Y1034745D03*
X489624Y1031245D03*
X491175Y1040766D03*
X491675Y1053145D03*
X486175Y1056766D03*
X491675Y1047266D03*
X507592Y128498D03*
Y136498D03*
Y132498D03*
X529383Y161919D03*
Y157919D03*
Y166937D03*
X534107Y133207D03*
Y149207D03*
Y137207D03*
Y141207D03*
Y145207D03*
Y153207D03*
X563089Y321993D03*
X570237Y1268118D03*
X581675Y1238075D03*
X588675Y1234075D03*
X613287Y1262988D03*
X613297Y1270888D03*
Y1274798D03*
X631161Y70040D03*
Y66040D03*
X645618Y444936D03*
X644471Y473877D03*
X644433Y469827D03*
X648846Y763766D03*
X645467Y1370789D03*
Y1380953D03*
Y1374914D03*
X643458Y1636815D03*
X656454Y453880D03*
X653006Y751266D03*
X659037Y763766D03*
X658087Y960966D03*
X659683Y1380836D03*
Y1376836D03*
X657483Y1645522D03*
X650483D03*
X672512Y417859D03*
X672516Y433862D03*
X672866Y429352D03*
X672666Y447202D03*
X672516Y441862D03*
X672566Y437732D03*
X672516Y457862D03*
Y453862D03*
Y465862D03*
X678547Y763766D03*
X677477Y1642042D03*
Y1629042D03*
X676913Y1646419D03*
X668316Y1700164D03*
X680460Y75627D03*
X688738Y763766D03*
X687788Y960966D03*
X683016Y1654500D03*
X689331Y1684735D03*
X700254Y524700D03*
X708248Y763766D03*
X696462Y1658337D03*
X718439Y763766D03*
X717489Y960966D03*
X719637Y1574283D03*
X718517Y1670830D03*
X725516Y380862D03*
X737948Y763766D03*
X724266Y1566333D03*
X725607Y1647997D03*
Y1652997D03*
X735016Y1663000D03*
X725634Y1685660D03*
X738242Y1688839D03*
X751244Y277399D03*
X746072Y573171D03*
X753006Y751266D03*
X748140Y763766D03*
X747190Y960966D03*
X742016Y1663000D03*
X754393Y273399D03*
X757555Y286632D03*
X767649Y763766D03*
X776168Y411344D03*
Y407344D03*
Y415344D03*
X775168Y419344D03*
Y427344D03*
X779768Y438504D03*
X774118Y446564D03*
X774016Y442500D03*
X777991Y763766D03*
X776891Y960966D03*
X798016Y295488D03*
X797907Y304062D03*
X789668Y475344D03*
X797350Y763765D03*
X803393Y268621D03*
X801186Y312773D03*
X806178Y508166D03*
X810411Y763765D03*
Y767665D03*
Y771465D03*
X806591Y960966D03*
X819230Y1486876D03*
Y1490876D03*
Y1496876D03*
Y1500876D03*
Y1506284D03*
Y1516284D03*
Y1510284D03*
Y1520284D03*
Y1530284D03*
Y1526284D03*
X842736Y220362D03*
X838095Y1281324D03*
X838223Y1285472D03*
X839529Y1291772D03*
X839525Y1296068D03*
X849736Y209362D03*
X849636Y216362D03*
X847025Y287602D03*
X849266Y1269785D03*
X849410Y1287438D03*
X889723Y1141058D03*
X897664Y1143953D03*
X911016Y853000D03*
X904016Y945000D03*
X930311Y193386D03*
X930111Y189386D03*
X928441Y201612D03*
X943016Y850500D03*
X935016Y894500D03*
X934016Y973500D03*
Y986500D03*
X936748Y1141058D03*
X944689Y1143953D03*
X935152Y1265636D03*
Y1282115D03*
X935199Y1278059D03*
X935117Y1269729D03*
X935223Y1273958D03*
X935056Y1294191D03*
X935136Y1290152D03*
X935172Y1286156D03*
X961016Y903500D03*
X958016Y1267000D03*
Y1279000D03*
Y1275000D03*
Y1271000D03*
X1008093Y1294268D03*
X1046956Y763765D03*
X1057148D03*
X1076657D03*
X1086849D03*
X1106357D03*
X1116550D03*
X1136058D03*
X1132323Y1649775D03*
X1136480Y1682518D03*
X1129025Y1682565D03*
Y1686065D03*
X1140016Y1679000D03*
X1146251Y763765D03*
X1165759D03*
X1180817Y751265D03*
X1175951Y763765D03*
X1195460D03*
X1208521D03*
X1203773Y960965D03*
X1229016Y1417000D03*
X1249313Y787397D03*
X1269693Y774324D03*
Y770324D03*
X1271693Y783324D03*
Y787324D03*
X1261693Y777824D03*
Y781824D03*
X1286768Y801299D03*
X1333693Y1203988D03*
X1333748Y1228559D03*
X1342907Y1224309D03*
X1362868Y1003765D03*
X1362193Y1030988D03*
Y1043488D03*
Y1037488D03*
X1364317Y1053265D03*
X1362817Y1049765D03*
X1360827Y1214637D03*
X1375817Y1007265D03*
X1369193Y1030988D03*
X1375817Y1028265D03*
X1369193Y1043488D03*
Y1037488D03*
X1375817Y1034265D03*
X1378817Y1040765D03*
X1379317Y1047265D03*
X1371817D03*
X1377317Y1056765D03*
X1371817Y1053265D03*
X1379317Y1060265D03*
X1378817Y1053265D03*
X1389193Y966488D03*
X1388817Y978265D03*
X1385317Y991265D03*
Y997765D03*
X1392817Y991265D03*
Y997765D03*
X1391824Y1032303D03*
X1386317Y1040765D03*
X1393817D03*
X1386317Y1047265D03*
X1393817D03*
Y1053265D03*
X1386317D03*
X1392317Y1056765D03*
X1384817D03*
X1390317Y1060265D03*
X1390193Y1071988D03*
X1401693Y969988D03*
X1407317Y985265D03*
X1400413D03*
X1407317Y991265D03*
X1400317D03*
Y997765D03*
X1407317D03*
X1401317Y1040765D03*
X1408317Y1047265D03*
X1401317D03*
X1408817Y1053265D03*
X1401317D03*
X1399317Y1056765D03*
X1406817D03*
X1402893Y1068488D03*
X1422317Y985265D03*
X1423915Y981765D03*
X1422317Y997765D03*
Y991265D03*
X1415817Y1038765D03*
Y1042765D03*
X1423317Y1047265D03*
X1423607Y1053265D03*
X1433193Y966488D03*
X1438817Y981765D03*
X1433317Y978265D03*
X1431317Y981765D03*
Y987765D03*
X1436817Y997765D03*
X1438817Y987765D03*
X1429817Y991265D03*
X1436817D03*
X1429817Y997765D03*
X1438814Y1013603D03*
Y1006122D03*
Y1009863D03*
Y1028563D03*
Y1017343D03*
Y1021083D03*
Y1024823D03*
Y1032303D03*
X1438317Y1040765D03*
X1430817D03*
Y1047265D03*
X1438317D03*
X1438568Y1053265D03*
X1434817Y1060265D03*
X1425317Y1056765D03*
X1432817D03*
X1431088Y1053265D03*
X1434693Y1071988D03*
X1446043Y535318D03*
Y539318D03*
X1453517Y981765D03*
X1446317D03*
X1444317Y991265D03*
X1453817Y1000765D03*
Y987765D03*
X1444317Y997765D03*
X1453817Y994265D03*
X1446317Y987765D03*
X1453736Y1015473D03*
X1453817Y1007265D03*
X1453736Y1022559D03*
Y1019016D03*
X1445817Y1040765D03*
X1452817D03*
X1453317Y1047265D03*
X1452817Y1053144D03*
X1447317Y1056765D03*
X1440317D03*
X1445817Y1053144D03*
Y1047265D03*
X1466773Y548977D03*
Y552977D03*
Y560977D03*
Y564977D03*
X1458773Y572977D03*
Y568977D03*
Y576977D03*
Y580977D03*
X1455693Y966488D03*
X1455393Y978265D03*
X1466693D03*
X1461317Y981765D03*
X1468317D03*
Y987765D03*
X1461317Y1000765D03*
X1468317Y994265D03*
Y1000765D03*
X1461317Y987765D03*
Y994265D03*
X1468317Y1015473D03*
Y1007265D03*
X1461317Y1015473D03*
Y1007265D03*
X1468317Y1019016D03*
Y1022559D03*
X1464317Y1027744D03*
X1461317Y1022559D03*
X1456817Y1027744D03*
X1461317Y1019016D03*
X1460317Y1040765D03*
X1454755Y1037265D03*
X1467317Y1040765D03*
X1458365Y1031244D03*
X1465766D03*
X1464317Y1034744D03*
X1460317Y1047265D03*
X1467817D03*
X1462317Y1056765D03*
X1456893Y1060265D03*
X1467817Y1053144D03*
X1454817Y1056765D03*
X1460317Y1053144D03*
X1456693Y1071988D03*
X1510773Y563977D03*
X1514773Y567977D03*
X1540393Y801185D03*
Y797185D03*
X1532893Y1264488D03*
X1540193D03*
X1547262Y804133D03*
X1557779Y1237662D03*
X1548268Y1268488D03*
Y1264488D03*
X1548133Y1274378D03*
X1548193Y1278988D03*
Y1282988D03*
X1547493Y1289938D03*
X1569609Y804063D03*
X1564614Y792552D03*
Y796552D03*
X1565193Y1234162D03*
X1560693Y1284108D03*
X1569518Y1299568D03*
X1576319Y1239866D03*
X1582463Y1256688D03*
Y1268388D03*
X1574153Y1286088D03*
X1576518Y1299568D03*
X1599693Y1274988D03*
Y1278988D03*
X1588993Y1295288D03*
Y1291288D03*
X1599693Y1286988D03*
X1599767Y1302895D03*
X1607460Y556730D03*
X1628817Y752765D03*
X1624987Y763765D03*
X1635179D03*
X1634229Y960965D03*
X1654688Y763765D03*
X1654086Y1416284D03*
X1657910Y1426945D03*
X1664880Y763765D03*
X1663930Y960965D03*
X1666351Y1416710D03*
X1670353Y1426686D03*
X1677791Y121762D03*
X1687441Y153762D03*
Y161762D03*
X1684389Y763765D03*
X1694581D03*
X1693631Y960965D03*
X1714090Y763765D03*
X1732381Y53651D03*
Y57651D03*
X1724282Y763765D03*
X1723332Y960965D03*
X1726979Y1663465D03*
Y1667965D03*
Y1658965D03*
X1743791Y763765D03*
X1753983D03*
X1753033Y960965D03*
X1760945Y1658956D03*
X1773491Y763765D03*
X1768779Y1676865D03*
X1786006Y46086D03*
X1783683Y763765D03*
X1782733Y960965D03*
X1811138Y174869D03*
G54D113*
X1156378Y133866D03*
X1173858Y207205D03*
X1391260Y174213D03*
G54D104*
X922441Y154311D03*
Y243799D03*
G54D123*
X1579532Y793506D03*
Y800986D03*
X1589178D03*
Y793506D03*
Y797246D03*
X1587601Y1337293D03*
Y1344773D03*
Y1351773D03*
Y1359253D03*
X1597247Y1337293D03*
Y1341033D03*
Y1344773D03*
Y1351773D03*
Y1355513D03*
Y1359253D03*
G54D105*
X928740Y321654D03*
G54D21*
X33738Y441130D03*
Y445519D03*
X41116Y1603396D03*
Y1623196D03*
X65296Y388462D03*
X65294Y393079D03*
X60705Y528205D03*
X60910Y1654387D03*
X81483Y1444500D03*
Y1448500D03*
X82150Y1629905D03*
X83842Y763766D03*
X103543D03*
X113543D03*
X133244D03*
X140483Y1425000D03*
X137483Y1429000D03*
X129983Y1436500D03*
X143375Y763700D03*
X162883Y763766D03*
X173045Y763666D03*
X192645Y763766D03*
X207642Y751266D03*
X202745Y763766D03*
X203906Y1658170D03*
X210741Y1658192D03*
X210513Y1664479D03*
X203564D03*
X222246Y763766D03*
X230598Y960966D03*
X235346Y763766D03*
X258883Y58400D03*
Y62400D03*
X250280Y111743D03*
X266054Y775410D03*
Y784788D03*
Y780588D03*
X277754Y793988D03*
Y797988D03*
X291624Y37420D03*
X339483Y582500D03*
Y578500D03*
X348640Y591335D03*
Y586415D03*
X356640Y558415D03*
Y562415D03*
Y570415D03*
Y574415D03*
X360821Y1198131D03*
X373276Y239452D03*
X369283Y544000D03*
Y548000D03*
X373414Y1192148D03*
X373483Y1187862D03*
Y1195862D03*
X373374Y1207538D03*
X389693Y1003766D03*
X389254Y1037488D03*
Y1031288D03*
Y1043488D03*
X389099Y1049766D03*
X391099Y1053266D03*
X394642Y1060266D03*
X385700Y1670046D03*
Y1673985D03*
X400640Y573415D03*
X404640Y577415D03*
X402642Y1007266D03*
Y1028266D03*
X405642Y1040766D03*
X402642Y1034266D03*
X396254Y1043488D03*
Y1031288D03*
Y1037488D03*
X398642Y1047266D03*
X405642Y1053266D03*
X406142Y1060266D03*
X396642Y1056766D03*
X404142D03*
X398642Y1053266D03*
X406142Y1047266D03*
X415754Y966488D03*
X415642Y978266D03*
X412142Y997766D03*
X419642Y991266D03*
Y997766D03*
X412142Y991266D03*
X420642Y1040766D03*
X413142D03*
X418649Y1032304D03*
X420642Y1053266D03*
X413142D03*
X419142Y1056766D03*
X417142Y1060266D03*
X411642Y1056766D03*
X420642Y1047266D03*
X413142D03*
X417254Y1071988D03*
X416983Y1653500D03*
X412983Y1672500D03*
X428654Y970088D03*
X434142Y985266D03*
X427254D03*
X434142Y997766D03*
Y991266D03*
X427142D03*
Y997766D03*
X428142Y1040766D03*
X433642Y1056766D03*
X428142Y1053266D03*
X426142Y1056766D03*
X435642Y1053266D03*
X428142Y1047266D03*
X435142D03*
X430254Y1068488D03*
X429960Y1608370D03*
X427303Y1615168D03*
X438983Y1626000D03*
X449676Y106490D03*
Y102490D03*
X450642Y981766D03*
X449142Y985266D03*
Y997766D03*
Y991266D03*
X442642Y1042766D03*
Y1038766D03*
X450432Y1053266D03*
X452142Y1056766D03*
X450142Y1047266D03*
X441983Y1630000D03*
X460254Y966488D03*
X460142Y978266D03*
X458142Y981766D03*
X465642D03*
X463642Y991266D03*
X456642Y997766D03*
X463642D03*
X465642Y987766D03*
X456642Y991266D03*
X458142Y987766D03*
X465639Y1013604D03*
Y1009864D03*
Y1006123D03*
Y1017344D03*
Y1024824D03*
Y1028564D03*
Y1021084D03*
X457642Y1040766D03*
X465639Y1032304D03*
X465142Y1040766D03*
Y1047266D03*
X459642Y1056766D03*
X465393Y1053266D03*
X467142Y1056766D03*
X461642Y1060266D03*
X457913Y1053266D03*
X457642Y1047266D03*
X461254Y1071988D03*
X477901Y285693D03*
X482518Y966489D03*
X473142Y981766D03*
X480642D03*
X482218Y978266D03*
X480642Y1000766D03*
Y994266D03*
Y987766D03*
X473142D03*
X471142Y997766D03*
Y991266D03*
X480561Y1015474D03*
X480642Y1007266D03*
X483642Y1027745D03*
X480561Y1019017D03*
Y1022560D03*
X481580Y1037266D03*
X472642Y1040766D03*
X479642D03*
X472642Y1047266D03*
X480142D03*
X474142Y1056766D03*
X479642Y1053145D03*
X481642Y1056766D03*
X472642Y1053145D03*
X483754Y1071988D03*
X499025Y143545D03*
Y147545D03*
Y138598D03*
X493518Y978266D03*
X488142Y981766D03*
X495142D03*
Y994266D03*
X488142Y1000766D03*
X495142D03*
Y987766D03*
X488142Y994266D03*
Y987766D03*
Y1007266D03*
Y1015474D03*
X495142D03*
Y1007266D03*
X491142Y1027745D03*
X495142Y1022560D03*
X488142Y1019017D03*
Y1022560D03*
X495142Y1019017D03*
X487142Y1040766D03*
X485190Y1031245D03*
X491142Y1034745D03*
X492591Y1031245D03*
X494142Y1040766D03*
X487142Y1047266D03*
Y1053145D03*
X494642D03*
X489142Y1056766D03*
X494642Y1047266D03*
X510559Y128498D03*
Y136498D03*
Y132498D03*
X537074Y133207D03*
Y149207D03*
Y137207D03*
Y141207D03*
Y145207D03*
Y153207D03*
X532350Y161919D03*
Y157919D03*
Y166937D03*
X566056Y321993D03*
X573204Y1268118D03*
X584642Y1238075D03*
X591642Y1234075D03*
X616254Y1262988D03*
X616264Y1270888D03*
Y1274798D03*
X634128Y70040D03*
Y66040D03*
X648585Y444936D03*
X647438Y473877D03*
X647400Y469827D03*
X648434Y1370789D03*
Y1380953D03*
Y1374914D03*
X646425Y1636815D03*
X659421Y453880D03*
X655973Y751266D03*
X662004Y763766D03*
X651813D03*
X661054Y960966D03*
X662650Y1380836D03*
Y1376836D03*
X660450Y1645522D03*
X653450D03*
X675479Y417859D03*
X675483Y433862D03*
X675833Y429352D03*
X675633Y447202D03*
X675483Y441862D03*
X675533Y437732D03*
X675483Y457862D03*
Y453862D03*
Y465862D03*
X671283Y1700164D03*
X683427Y75627D03*
X691705Y763766D03*
X681514D03*
X690755Y960966D03*
X680444Y1642042D03*
Y1629042D03*
X685983Y1654500D03*
X679880Y1646419D03*
X692298Y1684735D03*
X703221Y524700D03*
X699429Y1658337D03*
X721406Y763766D03*
X711215D03*
X720456Y960966D03*
X722604Y1574283D03*
X721484Y1670830D03*
X728483Y380862D03*
X727233Y1566333D03*
X728574Y1647997D03*
Y1652997D03*
X737983Y1663000D03*
X728601Y1685660D03*
X749039Y573171D03*
X751107Y763766D03*
X740915D03*
X750157Y960966D03*
X744983Y1663000D03*
X741209Y1688839D03*
X754211Y277399D03*
X757360Y273399D03*
X760522Y286632D03*
X755973Y751266D03*
X779135Y411344D03*
Y407344D03*
Y415344D03*
X778135Y419344D03*
Y427344D03*
X782735Y438504D03*
X777085Y446564D03*
X776983Y442500D03*
X780958Y763766D03*
X770616D03*
X779858Y960966D03*
X792635Y475344D03*
X806360Y268621D03*
X800983Y295488D03*
X804153Y312773D03*
X800874Y304062D03*
X809145Y508166D03*
X800317Y763765D03*
X809558Y960966D03*
X813378Y763765D03*
Y767665D03*
Y771465D03*
X822197Y1486876D03*
Y1490876D03*
Y1496876D03*
Y1500876D03*
Y1506284D03*
Y1516284D03*
Y1510284D03*
Y1520284D03*
Y1530284D03*
Y1526284D03*
X841062Y1281324D03*
X841190Y1285472D03*
X842496Y1291772D03*
X842492Y1296068D03*
X852703Y209362D03*
X852603Y216362D03*
X845703Y220362D03*
X849992Y287602D03*
X852233Y1269785D03*
X852377Y1287438D03*
X892690Y1141058D03*
X900631Y1143953D03*
X913983Y853000D03*
X906983Y945000D03*
X931408Y201612D03*
X933278Y193386D03*
X933078Y189386D03*
X945983Y850500D03*
X937983Y894500D03*
X936983Y973500D03*
Y986500D03*
X939715Y1141058D03*
X938119Y1265636D03*
Y1282115D03*
X938166Y1278059D03*
X938084Y1269729D03*
X938190Y1273958D03*
X938023Y1294191D03*
X938103Y1290152D03*
X938139Y1286156D03*
X947656Y1143953D03*
X960983Y1267000D03*
Y1279000D03*
Y1275000D03*
Y1271000D03*
X963983Y903500D03*
X1011060Y1294268D03*
X1049923Y763765D03*
X1060115D03*
X1079624D03*
X1089816D03*
X1109324D03*
X1119517D03*
X1139025D03*
X1135290Y1649775D03*
X1139447Y1682518D03*
X1131992Y1682565D03*
Y1686065D03*
X1149218Y763765D03*
X1142983Y1679000D03*
X1168726Y763765D03*
X1183784Y751265D03*
X1178918Y763765D03*
X1198427D03*
X1211488D03*
X1206740Y960965D03*
X1231983Y1417000D03*
X1252280Y787397D03*
X1272660Y774324D03*
Y770324D03*
X1274660Y783324D03*
Y787324D03*
X1264660Y777824D03*
Y781824D03*
X1289735Y801299D03*
X1336660Y1203988D03*
X1345874Y1224309D03*
X1336715Y1228559D03*
X1363794Y1214637D03*
X1378784Y1007265D03*
X1365835Y1003765D03*
X1372160Y1030988D03*
X1365160D03*
X1378784Y1028265D03*
X1372160Y1043488D03*
X1365160D03*
Y1037488D03*
X1372160D03*
X1378784Y1034265D03*
X1367284Y1053265D03*
X1365784Y1049765D03*
X1374784Y1047265D03*
Y1053265D03*
X1392160Y966488D03*
X1391784Y978265D03*
X1388284Y991265D03*
Y997765D03*
X1389284Y1040765D03*
X1381784D03*
X1389284Y1047265D03*
X1382284D03*
X1380284Y1056765D03*
X1389284Y1053265D03*
X1387784Y1056765D03*
X1393284Y1060265D03*
X1382284D03*
X1381784Y1053265D03*
X1393160Y1071988D03*
X1404660Y969988D03*
X1403380Y985265D03*
X1403284Y991265D03*
X1395784D03*
Y997765D03*
X1403284D03*
X1394791Y1032303D03*
X1404284Y1040765D03*
X1396784D03*
Y1047265D03*
X1404284D03*
X1396784Y1053265D03*
X1395284Y1056765D03*
X1404284Y1053265D03*
X1402284Y1056765D03*
X1405860Y1068488D03*
X1410284Y985265D03*
Y991265D03*
Y997765D03*
X1418784Y1038765D03*
Y1042765D03*
X1411284Y1047265D03*
X1411784Y1053265D03*
X1409784Y1056765D03*
X1436160Y966488D03*
X1425284Y985265D03*
X1426882Y981765D03*
X1436284Y978265D03*
X1434284Y981765D03*
Y987765D03*
X1425284Y997765D03*
X1432784Y991265D03*
X1425284D03*
X1432784Y997765D03*
X1433784Y1040765D03*
Y1047265D03*
X1426284D03*
X1437784Y1060265D03*
X1428284Y1056765D03*
X1435784D03*
X1434055Y1053265D03*
X1426574D03*
X1437660Y1071988D03*
X1449010Y535318D03*
Y539318D03*
X1441784Y981765D03*
X1449284D03*
X1447284Y991265D03*
X1439784Y997765D03*
X1441784Y987765D03*
X1439784Y991265D03*
X1447284Y997765D03*
X1449284Y987765D03*
X1441781Y1013603D03*
Y1006122D03*
Y1009863D03*
Y1028563D03*
Y1017343D03*
Y1021083D03*
Y1024823D03*
Y1032303D03*
X1441284Y1040765D03*
X1448784D03*
X1441284Y1047265D03*
X1441535Y1053265D03*
X1450284Y1056765D03*
X1443284D03*
X1448784Y1053144D03*
Y1047265D03*
X1461740Y572977D03*
Y568977D03*
Y576977D03*
Y580977D03*
X1458660Y966488D03*
X1458360Y978265D03*
X1456484Y981765D03*
X1464284D03*
X1456784Y1000765D03*
X1464284D03*
X1456784Y987765D03*
X1464284D03*
Y994265D03*
X1456784D03*
X1456703Y1015473D03*
X1464284D03*
Y1007265D03*
X1456784D03*
X1456703Y1022559D03*
X1467284Y1027744D03*
X1464284Y1022559D03*
X1456703Y1019016D03*
X1459784Y1027744D03*
X1464284Y1019016D03*
X1463284Y1040765D03*
X1457722Y1037265D03*
X1455784Y1040765D03*
X1461332Y1031244D03*
X1468733D03*
X1467284Y1034744D03*
X1463284Y1047265D03*
X1456284D03*
X1465284Y1056765D03*
X1455784Y1053144D03*
X1459860Y1060265D03*
X1457784Y1056765D03*
X1463284Y1053144D03*
X1459660Y1071988D03*
X1469740Y548977D03*
Y552977D03*
Y560977D03*
Y564977D03*
X1469660Y978265D03*
X1471284Y981765D03*
Y987765D03*
Y994265D03*
Y1000765D03*
Y1015473D03*
Y1007265D03*
Y1019016D03*
Y1022559D03*
X1470284Y1040765D03*
X1470784Y1047265D03*
Y1053144D03*
X1513740Y563977D03*
X1517740Y567977D03*
X1543360Y801185D03*
Y797185D03*
X1535860Y1264488D03*
X1543160D03*
X1550229Y804133D03*
X1551235Y1268488D03*
Y1264488D03*
X1551100Y1274378D03*
X1551160Y1278988D03*
Y1282988D03*
X1550460Y1289938D03*
X1572576Y804063D03*
X1567581Y792552D03*
Y796552D03*
X1560746Y1237662D03*
X1568160Y1234162D03*
X1563660Y1284108D03*
X1572485Y1299568D03*
X1579286Y1239866D03*
X1585430Y1256688D03*
Y1268388D03*
X1577120Y1286088D03*
X1579485Y1299568D03*
X1602660Y1274988D03*
Y1278988D03*
X1591960Y1295288D03*
Y1291288D03*
X1602660Y1286988D03*
X1602734Y1302895D03*
X1610427Y556730D03*
X1631784Y752765D03*
X1627954Y763765D03*
X1638146D03*
X1637196Y960965D03*
X1657655Y763765D03*
X1657053Y1416284D03*
X1660877Y1426945D03*
X1667847Y763765D03*
X1666897Y960965D03*
X1669318Y1416710D03*
X1673320Y1426686D03*
X1680758Y121762D03*
X1690408Y153762D03*
Y161762D03*
X1687356Y763765D03*
X1697548D03*
X1696598Y960965D03*
X1717057Y763765D03*
X1735348Y53651D03*
Y57651D03*
X1727249Y763765D03*
X1726299Y960965D03*
X1729946Y1663465D03*
Y1667965D03*
Y1658965D03*
X1746758Y763765D03*
X1756950D03*
X1756000Y960965D03*
X1763912Y1658956D03*
X1776458Y763765D03*
X1771746Y1676865D03*
X1788973Y46086D03*
X1786650Y763765D03*
X1785700Y960965D03*
X1814105Y174869D03*
G54D30*
X57646Y12480D03*
X137272D03*
X186622D03*
X266858D03*
X315598D03*
X502528Y33267D03*
X582154D03*
X631504D03*
X711740D03*
X760480D03*
X1183858Y207205D03*
Y217205D03*
X1173858D03*
X1193858Y207205D03*
Y217205D03*
X1351260Y164213D03*
Y174213D03*
X1361260Y164213D03*
Y174213D03*
X1371260Y164213D03*
X1381260D03*
X1371260Y174213D03*
X1381260D03*
X1391260Y164213D03*
X1532055Y12480D03*
X1611681D03*
X1661031D03*
X1741267D03*
X1790007D03*
G54D114*
X1225530Y60384D03*
X1233404D03*
X1241278D03*
X1439049Y87432D03*
X1454797D03*
X1446923D03*
G54D12*
X11782Y167036D03*
X18691Y167208D03*
X22409Y230021D03*
X19684Y237154D03*
X17292Y290137D03*
X16681Y1451841D03*
X35689Y301357D03*
X36722Y327797D03*
X35740Y363337D03*
X39320Y392269D03*
X29962Y401000D03*
X33350Y434992D03*
X27520D03*
X38620Y447202D03*
X38480Y441482D03*
X39967Y526709D03*
X30562Y533055D03*
X38181Y1451841D03*
X45423Y197224D03*
Y212224D03*
Y202224D03*
Y207224D03*
X42449Y282916D03*
Y277798D03*
X47892Y290137D03*
X41492Y298207D03*
X47892Y295452D03*
X40500Y288500D03*
X55254Y292892D03*
X42449Y312916D03*
Y307798D03*
X46988Y324563D03*
X55190Y360862D03*
X42809D03*
X40940Y387302D03*
X53825Y421746D03*
X55099Y1298676D03*
Y1292676D03*
X44019Y1518990D03*
X47735Y1584885D03*
X47973Y1589981D03*
X43633Y1606896D03*
X43933Y1613818D03*
X47633Y1600896D03*
X53633Y1629896D03*
X41208Y1619896D03*
X41427Y1668587D03*
X52052Y1684027D03*
X66650Y265316D03*
X62930Y282866D03*
X66289Y301357D03*
X62930Y312866D03*
X57920Y443702D03*
Y448702D03*
X65391Y524549D03*
X62142Y539495D03*
X64883Y748766D03*
X61620Y768510D03*
X56440Y766180D03*
X62181Y1451841D03*
X56218Y1535114D03*
X66229Y1549536D03*
X57850Y1542141D03*
X57811Y1598061D03*
X58633Y1587481D03*
X63633D03*
X58633Y1629896D03*
X64133Y1627896D03*
X64633Y1632896D03*
X70127Y1687362D03*
X82026Y143491D03*
X71659Y149191D03*
X71779Y161194D03*
X71500Y390812D03*
X71772Y421746D03*
X76378Y1406622D03*
X83441Y1430500D03*
X72375Y1604365D03*
X74133Y1610896D03*
X79679Y1605289D03*
X70567Y1625603D03*
X72255Y1616730D03*
X74134Y1621396D03*
X75380Y1627622D03*
X79164Y1636992D03*
X78127Y1687362D03*
X82500Y1698511D03*
Y1706511D03*
X82000Y1716331D03*
Y1724331D03*
X92197Y143853D03*
X87137Y143663D03*
X93775Y197241D03*
Y212241D03*
Y207241D03*
Y202241D03*
X87654Y376026D03*
X87520Y386502D03*
X92159Y750500D03*
X87260Y766947D03*
X90150Y1314560D03*
X93000Y1444500D03*
X88293Y1446638D03*
X86181Y1451841D03*
X93296Y1549142D03*
X93318Y1542141D03*
X96101Y1696469D03*
X96555Y1705508D03*
X95400Y1719741D03*
X95460Y1725241D03*
X104829Y151191D03*
X107931Y158767D03*
X100818Y168906D03*
X105296Y1375946D03*
X101995Y1388247D03*
X111600Y1403100D03*
X101637Y1432938D03*
X102076Y1427833D03*
X102398Y1440000D03*
X113500Y1455600D03*
X112100Y1467500D03*
X100439Y1667361D03*
X100915Y1679564D03*
X106448Y1696436D03*
X107500Y1707450D03*
X120016Y300654D03*
Y320631D03*
X122159Y750266D03*
X116878Y766757D03*
X122050Y1403750D03*
X129200Y1401000D03*
X126000Y1414000D03*
X116700Y1415700D03*
Y1410500D03*
X116900Y1449000D03*
X119100Y1460300D03*
X124312Y1633488D03*
X115353Y1695941D03*
X127710Y1700166D03*
X120052Y1712450D03*
X127290Y1705666D03*
X125183Y1716741D03*
X127168Y1721695D03*
X129020Y1726741D03*
X134812Y530955D03*
X140471Y670445D03*
X134902Y668506D03*
X140600Y683029D03*
X134902Y686074D03*
X140265Y1297380D03*
X137896Y1375946D03*
X138000Y1400600D03*
X134800Y1408100D03*
X133349Y1434651D03*
X141500Y1433500D03*
X139500Y1446000D03*
X133100Y1444100D03*
X138013Y1440487D03*
X133120Y1454751D03*
X141028Y1454705D03*
X137386Y1626412D03*
X131353Y1696062D03*
X139353D03*
X143000Y1701011D03*
Y1709166D03*
X149231Y224204D03*
X148228Y216118D03*
X158380Y419760D03*
X147450Y423860D03*
X154770Y441830D03*
X147810Y475710D03*
X146982Y526997D03*
X159513Y674855D03*
X152705Y683218D03*
X151659Y749766D03*
X146663Y766347D03*
X156477Y1447733D03*
X154305Y1453101D03*
X159000Y1525480D03*
X149171Y1616759D03*
X159427Y1687843D03*
Y1696652D03*
X152605Y1715941D03*
X149338Y1705603D03*
X146000Y1718241D03*
X155740Y1729726D03*
X146483Y1725636D03*
X162830Y396930D03*
X172010Y474900D03*
X163372Y670863D03*
X172725Y667898D03*
X162482Y679319D03*
X161735Y684456D03*
X172725Y679230D03*
X172965Y1297380D03*
X170266Y1344588D03*
X170596Y1375946D03*
X163148Y1474504D03*
X172180Y1490210D03*
X172070Y1495550D03*
X162740Y1713172D03*
X171925Y1708428D03*
X171945Y1730693D03*
X162740Y1723886D03*
X187250Y129674D03*
X189290Y396730D03*
X177675Y419260D03*
X185160Y419220D03*
X181550Y441290D03*
X181159Y750766D03*
X176326Y766615D03*
X186682Y1344588D03*
X176510Y1509270D03*
X174630Y1522540D03*
X176265Y1515524D03*
X180127Y1551756D03*
X182115Y1572260D03*
X181099Y1656804D03*
X175927Y1651506D03*
X184139Y1651088D03*
X179443Y1661581D03*
X182533Y1676854D03*
X184340Y1718000D03*
X178385Y1715441D03*
X178376Y1720559D03*
X195979Y109462D03*
X203061Y131158D03*
X201024Y571472D03*
X200754Y595174D03*
X200405Y632385D03*
X203496Y1375946D03*
X200488Y1557334D03*
X199747Y1675603D03*
X197780Y1696973D03*
X200478Y1701758D03*
X200448Y1690771D03*
X202076Y1717845D03*
X189760Y1713061D03*
X203510Y1712441D03*
X189760Y1723041D03*
X203655Y1723000D03*
X214107Y113022D03*
X205489Y142790D03*
X217687Y522453D03*
X218493Y684406D03*
X210993Y691906D03*
X218493Y699406D03*
X212400Y750200D03*
X215753Y767266D03*
X205865Y1297380D03*
X212365Y1705403D03*
X224055Y127146D03*
X233284Y137195D03*
X233653Y162074D03*
X223687Y522453D03*
X229687D03*
X233024Y567572D03*
X233493Y676906D03*
Y684406D03*
X225993Y691906D03*
Y706906D03*
X230771Y1259005D03*
X229994Y1344971D03*
X223671Y1546805D03*
X230052Y1559984D03*
X238059Y26235D03*
X235697Y21585D03*
X241306Y20325D03*
X246356Y26855D03*
X248816Y48965D03*
X239816Y54365D03*
X248487Y68690D03*
X242920Y67915D03*
X238846Y72977D03*
X235186Y98067D03*
X242215Y151788D03*
X236104Y151996D03*
X245486Y159705D03*
X240413Y360867D03*
X248493Y684406D03*
X240200Y766300D03*
X247058Y1344988D03*
X236296Y1375946D03*
X251106Y12615D03*
X257516Y51565D03*
X251793Y100846D03*
X252800Y114800D03*
X252195Y144320D03*
X249735Y152694D03*
X262886Y147391D03*
X253024Y567572D03*
Y587572D03*
Y607572D03*
X263493Y684406D03*
X263287Y740260D03*
X257071Y772770D03*
X252079Y1290037D03*
X251249Y1560542D03*
X275116Y28565D03*
X275896Y48875D03*
X266420Y39120D03*
X265365Y49171D03*
X267931Y59250D03*
X267995Y68344D03*
X273616Y96665D03*
X264293Y120972D03*
X269487Y121095D03*
X275793Y120248D03*
X266000Y125800D03*
X276821Y140465D03*
X264574Y159206D03*
X269925Y217700D03*
X274993Y522052D03*
X265100Y595078D03*
X267601Y608378D03*
X271571Y644796D03*
X265782Y653947D03*
X270857Y668515D03*
X271161Y780588D03*
X274282Y786741D03*
X272395Y1329656D03*
X264085Y1339175D03*
X267918Y1508216D03*
X264671Y1512470D03*
X264770Y1518000D03*
X269378Y1555103D03*
X286996Y20365D03*
X290795Y28365D03*
X287988Y54893D03*
X293157Y50525D03*
X286996Y139865D03*
X285865Y596970D03*
X290865Y609470D03*
X293817Y687986D03*
X287995Y1553934D03*
X295516Y26365D03*
X300244Y28365D03*
X299496Y22865D03*
X303252Y38199D03*
X295308Y43227D03*
X296337Y55855D03*
X298542Y51088D03*
X303711Y50860D03*
X301107Y75676D03*
X305820Y73693D03*
X301780Y82900D03*
X299002Y88700D03*
X307816Y95727D03*
X299628Y149203D03*
X299624Y158706D03*
X306528Y256528D03*
X294299Y577188D03*
X302130Y584160D03*
X305865Y596970D03*
X304449Y609570D03*
X304301Y679037D03*
X296117Y774610D03*
X305175Y1243788D03*
X305291Y1329628D03*
X304505Y1509298D03*
X303369Y1520193D03*
X305148Y1515299D03*
X303406Y1557752D03*
X323036Y73125D03*
X310455Y75895D03*
X320190Y77648D03*
X322871Y84321D03*
X316982Y89003D03*
X322174Y97472D03*
Y112472D03*
Y127472D03*
X323646Y147120D03*
Y152120D03*
X314780Y545716D03*
X322955Y556148D03*
X311349Y609632D03*
X326475Y182855D03*
X331780Y182900D03*
X324406Y367744D03*
X334744Y566086D03*
X326393Y708136D03*
X328887Y794660D03*
X338195Y1329571D03*
X326277Y1560681D03*
X343036Y122525D03*
X343446Y131170D03*
X339914Y165170D03*
X344984Y199299D03*
X352000Y230643D03*
Y235643D03*
X353288Y578508D03*
X342275Y1546793D03*
X349426Y1560262D03*
X366874Y135157D03*
X366771Y127665D03*
X355910Y223847D03*
X365739Y221871D03*
X365559Y238896D03*
X357600Y543080D03*
X363100Y585960D03*
X360467Y581734D03*
X359854Y707868D03*
X364671Y824846D03*
X359371Y824688D03*
X360071Y831388D03*
X359071Y838888D03*
X361922Y1206891D03*
X357271Y1208988D03*
X356430Y1546724D03*
X375920Y146577D03*
X377118Y222229D03*
X370327Y228951D03*
X370352Y235455D03*
X382184Y466351D03*
X378976Y479226D03*
X375410Y552254D03*
X375271Y542191D03*
X369271Y600138D03*
X373477Y593338D03*
X370575Y1243845D03*
X371089Y1329865D03*
X373971Y1559565D03*
X375050Y1639400D03*
X371823Y1644516D03*
X370533Y1658605D03*
X374962Y1648511D03*
X372953Y1653197D03*
X373330Y1668539D03*
X391600Y121178D03*
X387712Y147441D03*
X395590Y147010D03*
X391635Y161091D03*
X397184Y507101D03*
X387440Y525154D03*
X392554Y557081D03*
X394168Y568482D03*
X386071Y587138D03*
X393315Y707936D03*
X387446Y1207488D03*
X395267Y1358621D03*
X395980Y1508216D03*
X392792Y1512252D03*
X392830Y1518020D03*
X392936Y1557334D03*
X389276Y1568413D03*
X393322Y1573347D03*
X388784Y1581801D03*
X393005Y1592304D03*
X387805Y1604802D03*
X394824Y1629713D03*
X394000Y1621500D03*
X389824Y1629713D03*
X389000Y1621500D03*
X384824Y1629713D03*
X406243Y100076D03*
X403734Y110326D03*
X410678Y159140D03*
X411299Y212096D03*
X411940Y240501D03*
X410984Y496649D03*
X410111Y572608D03*
X403461Y1263319D03*
X403577Y1349102D03*
X408895Y1553644D03*
X407198Y1564990D03*
X401249Y1564422D03*
X405758Y1557900D03*
X403163Y1579357D03*
X404669Y1594317D03*
X401667Y1602636D03*
X400380Y1621500D03*
X408994Y1642292D03*
X404640Y1637425D03*
X412000Y1647177D03*
X403844Y1665769D03*
X406500Y1672500D03*
X405000Y1683500D03*
X416549Y66365D03*
Y71665D03*
X427300Y71300D03*
X419900Y96620D03*
X414100D03*
X422936Y223501D03*
X420115Y230323D03*
Y240501D03*
Y235442D03*
X419984Y508000D03*
X425152Y690136D03*
X415158Y774175D03*
X424107Y1553934D03*
X424488Y1565400D03*
X413540Y1556646D03*
X419254Y1566828D03*
X427081Y1581620D03*
X425166Y1602365D03*
X423722Y1625728D03*
X421500Y1657500D03*
X423500Y1652500D03*
X420000Y1668075D03*
X417000Y1683500D03*
X433673Y73960D03*
X428149Y65016D03*
X429685Y88657D03*
X431359Y82589D03*
X429997Y166400D03*
X441997D03*
X436103Y158594D03*
X438200Y212096D03*
X431299Y212095D03*
X437440Y237270D03*
X442710Y237990D03*
X435710Y250340D03*
X440710D03*
X437084Y501865D03*
X442084Y511870D03*
X440030Y1508070D03*
X439480Y1520193D03*
X441259Y1515299D03*
X439935Y1532600D03*
X431923Y1565790D03*
X440769Y1556778D03*
X433440Y1581700D03*
X439980Y1599330D03*
X429947Y1594398D03*
X433012Y1621612D03*
X437910Y1638091D03*
X432000Y1650000D03*
X440075Y1650073D03*
X445267Y82124D03*
X448038Y158659D03*
X445997Y170701D03*
X448499Y212036D03*
X443299Y212095D03*
X456231Y227764D03*
Y232883D03*
X446710Y249340D03*
X453269Y478388D03*
X443683Y502256D03*
X447084Y511870D03*
X457084D03*
X457356Y665536D03*
X446686Y744660D03*
X451740Y1302070D03*
Y1382070D03*
X445873Y1596163D03*
X444128Y1604200D03*
X446182Y1625555D03*
X462000Y147090D03*
X472000D03*
X465997Y166400D03*
X457997D03*
X471371Y227764D03*
Y222764D03*
X460567Y225205D03*
Y235442D03*
X460624Y230323D03*
X470243Y285693D03*
X460441Y499842D03*
X468638Y514096D03*
X465766Y524991D03*
X462490Y734528D03*
X471740Y1302070D03*
Y1322070D03*
Y1362070D03*
Y1382070D03*
X460712Y1559986D03*
X459500Y1659000D03*
X468350Y1645351D03*
X468075Y1662500D03*
X470309Y1689000D03*
X468575Y1704000D03*
Y1731000D03*
X479400Y90574D03*
X482000Y147090D03*
X486682Y197516D03*
X487620Y270400D03*
X479870D03*
X483823Y285893D03*
X484063Y305669D03*
X481239Y312352D03*
X479058Y720660D03*
X483722Y1560823D03*
X483500Y1658500D03*
X479500Y1666500D03*
X473500Y1662500D03*
X476000Y1680000D03*
X478500Y1701000D03*
X474000Y1704000D03*
X478500Y1714500D03*
X500674Y116261D03*
X495232Y189516D03*
X496831Y205030D03*
X494144Y221370D03*
X500209Y227881D03*
Y233000D03*
X491859D03*
X500119Y243173D03*
X489232Y290418D03*
X488405Y578572D03*
X501171Y630087D03*
X490976Y639036D03*
X494862Y708028D03*
X491740Y1302070D03*
Y1322070D03*
Y1342070D03*
Y1362070D03*
Y1382070D03*
X487801Y1546725D03*
X502750Y111276D03*
X505315Y196944D03*
X504351Y202776D03*
X512076Y206404D03*
X508001Y220166D03*
X507569Y1559567D03*
X524713Y33346D03*
X529713D03*
X524400Y167680D03*
X519601Y196117D03*
X524798Y299035D03*
Y309035D03*
X529095Y452049D03*
X524752Y604936D03*
X530493Y628906D03*
X527458Y681460D03*
X518075Y845663D03*
X532091Y1508216D03*
X528890Y1517960D03*
X529025Y1512306D03*
X527651Y1559707D03*
X544721Y42892D03*
X539721Y42862D03*
X534277Y224930D03*
X538613Y227882D03*
Y238119D03*
X534277Y230441D03*
X538613Y233000D03*
X538968Y258261D03*
X534455Y428561D03*
X543997Y1654500D03*
X553651Y48842D03*
X550972Y42902D03*
X561721Y41024D03*
X556351Y41538D03*
X548610Y48082D03*
X558500Y138880D03*
X549248Y237652D03*
Y230441D03*
X558968Y258403D03*
X562030Y372872D03*
X562208Y383668D03*
Y404717D03*
Y397599D03*
X555727Y479968D03*
X550493Y563906D03*
Y583906D03*
Y603906D03*
Y628906D03*
X552169Y1553934D03*
X565185Y47982D03*
X575331Y47672D03*
X573191Y42912D03*
X570209Y47982D03*
X566771Y41133D03*
X571933Y66587D03*
X563951Y153640D03*
Y148640D03*
Y160644D03*
X572003Y164356D03*
X569004Y225496D03*
X570823Y294893D03*
X564400Y317260D03*
X575913Y413287D03*
X570863Y410728D03*
X572121Y437038D03*
X564407Y431638D03*
X563763Y486350D03*
X570493Y563906D03*
Y583906D03*
Y603906D03*
Y628906D03*
X575600Y1257350D03*
X563596Y1268118D03*
X568605Y1509322D03*
X567542Y1520193D03*
X569321Y1515299D03*
X566978Y1555522D03*
X591938Y46308D03*
X591070Y60201D03*
X586953Y63441D03*
X590501Y86909D03*
X580098Y96439D03*
X586394Y95948D03*
X591811Y97421D03*
X589203Y164356D03*
Y169415D03*
X588215Y214079D03*
X588968Y240112D03*
X590900Y258260D03*
X585303Y303170D03*
Y318170D03*
X585585Y372052D03*
X577482Y383668D03*
X587710Y399287D03*
Y404287D03*
X588798Y435949D03*
X588723Y427949D03*
X589507Y462559D03*
X583116Y476745D03*
X581335Y472100D03*
X580614Y776454D03*
X584271Y1263988D03*
X578484Y1268948D03*
X585386Y1559357D03*
X602837Y32910D03*
X603064Y48023D03*
X599284Y42481D03*
X597956Y48047D03*
X606585Y43529D03*
X599295Y100747D03*
X606183Y95873D03*
X597275Y94922D03*
X596068Y106798D03*
X597769Y153640D03*
Y148640D03*
X604293Y193185D03*
X597293Y193186D03*
X602294Y203786D03*
X598968Y238878D03*
X598208Y383668D03*
X593758Y415850D03*
X597500Y483500D03*
X602584Y1246888D03*
X596944Y1270115D03*
X605771Y1263098D03*
X598112Y1264365D03*
X619563Y49193D03*
X615587Y45611D03*
X618182Y100786D03*
X610009Y100748D03*
X614282Y95873D03*
X618801Y165356D03*
Y175534D03*
Y170415D03*
X608794Y203786D03*
X621585Y331358D03*
X613565Y350819D03*
X613482Y383668D03*
X617985Y401728D03*
X618680Y511302D03*
X611896Y538178D03*
X607091Y528168D03*
X620234Y751615D03*
X619695Y758764D03*
X607671Y1246088D03*
X615591Y1282038D03*
X608148Y1373890D03*
X612041Y1379093D03*
X609241Y1388552D03*
X615921Y1546725D03*
X609093Y1560264D03*
X624634Y48104D03*
X627881Y57120D03*
X622207Y60573D03*
X636070Y76336D03*
X626642Y71365D03*
X632096Y80536D03*
X622156Y95948D03*
X626208Y100861D03*
X630900Y118920D03*
X622705Y285305D03*
X636500Y360362D03*
X634105Y404652D03*
X635058Y399700D03*
X627925Y421966D03*
X622800Y461348D03*
X627880Y455310D03*
X627364Y478823D03*
X635567Y671774D03*
X624537Y765541D03*
X632479Y781595D03*
X629511Y789048D03*
X626112Y1301920D03*
X632983Y1297148D03*
X633406Y1358576D03*
X634776Y1353739D03*
X624795Y1373257D03*
X624976Y1378313D03*
X630195Y1384263D03*
X625195Y1383457D03*
X622352Y1393285D03*
X630523Y1392554D03*
X635849Y1393376D03*
X629593Y1560543D03*
X623205Y1639099D03*
X623175Y1644227D03*
X631961Y1651949D03*
X633422Y1673488D03*
X635491Y1696845D03*
X635472Y1711808D03*
X642157Y44695D03*
X639876Y49193D03*
X651042Y41545D03*
X647987Y47606D03*
X646042Y41545D03*
X640653Y58274D03*
X645814Y60051D03*
X650846Y74074D03*
X647938Y83795D03*
X642607Y94116D03*
X642394Y131172D03*
X645752Y134988D03*
X649871Y181942D03*
X642617Y389299D03*
X637314Y393680D03*
X651279Y404458D03*
X648500Y453862D03*
X644849Y495582D03*
X640076Y497964D03*
X649592Y540078D03*
X646151Y535227D03*
X650228Y674761D03*
X640990Y750766D03*
X648838Y1561659D03*
X646630Y1626990D03*
X646522Y1621820D03*
X645320Y1633260D03*
X637524Y1642010D03*
X642716Y1653939D03*
X637218Y1654131D03*
X644905Y1646491D03*
X639800Y1646650D03*
X647460Y1662952D03*
X640846Y1665189D03*
X650158Y1687189D03*
X643041Y1682883D03*
X650505Y1681978D03*
X637206Y1676799D03*
X643300Y1677689D03*
X651143Y1706162D03*
X644975Y1725236D03*
X654117Y29099D03*
X654582Y45448D03*
X653892Y54314D03*
X661601Y75562D03*
X661588Y69662D03*
X658228Y88447D03*
X666200Y84862D03*
X654037Y96041D03*
X663915Y234476D03*
X658905Y341885D03*
X653523Y399987D03*
X652954Y394284D03*
X662000Y433862D03*
X666000Y429844D03*
X652763Y427866D03*
X657622Y437819D03*
X651853Y439518D03*
X666000Y473844D03*
X651937Y469576D03*
X660215Y483109D03*
X665689Y550294D03*
X660175Y679517D03*
X665417Y768090D03*
X665000Y1329100D03*
Y1349100D03*
X653376Y1365793D03*
X657916Y1362163D03*
X654992Y1380836D03*
X660153Y1508216D03*
X661710Y1514148D03*
X666092Y1553650D03*
X657430Y1555228D03*
X653542Y1649059D03*
X660389Y1654481D03*
X657801Y1676898D03*
X652379Y1676984D03*
X660930Y1730277D03*
X662120Y1720404D03*
X680864Y38190D03*
X674647D03*
X674036Y74522D03*
X667941Y80142D03*
X680800Y380280D03*
X676000Y378100D03*
X667090Y385150D03*
X679940Y400933D03*
X680171Y417859D03*
X680175Y445862D03*
Y458862D03*
X679648Y465862D03*
X678000Y477862D03*
Y482862D03*
X681213Y495658D03*
X680488Y504784D03*
X670490Y752266D03*
X680776Y1297506D03*
X678552Y1361408D03*
X669857Y1528502D03*
X667971Y1654404D03*
X669178Y1646627D03*
X673480Y1662668D03*
X680080Y1678937D03*
X667882Y1676962D03*
X671631Y1690786D03*
X667852Y1695577D03*
X667817Y1710439D03*
X667701Y1705043D03*
X684611Y41857D03*
X682291Y46822D03*
X692390Y46939D03*
X687835Y37850D03*
X687345Y46940D03*
X690028Y70142D03*
X688030Y76380D03*
X686891Y115868D03*
X685200Y377820D03*
X684794Y402268D03*
X683187Y413863D03*
X692996Y418358D03*
X694299Y413108D03*
X689269Y410420D03*
X685170Y426600D03*
X690073Y430971D03*
X683175Y433862D03*
X685960Y441530D03*
X690410Y437440D03*
X686044Y450305D03*
X692550Y446730D03*
X686452Y459585D03*
X690323Y481844D03*
X683175Y469862D03*
X690323Y468584D03*
X696242Y474904D03*
X693900Y492100D03*
X687310Y500453D03*
Y522141D03*
X690718Y578913D03*
X694996Y575081D03*
X695249Y768132D03*
X684350Y1448911D03*
X693495Y1519305D03*
X692209Y1620037D03*
X686808Y1643500D03*
X685578Y1637479D03*
X686867Y1651010D03*
X696336Y1668183D03*
X689395Y1665685D03*
X705666Y48010D03*
X697678Y47132D03*
X704201Y72112D03*
X699476Y69982D03*
X699398Y123668D03*
X701171Y130963D03*
X704709Y125586D03*
X707500Y368862D03*
X700300Y382502D03*
X707500Y382362D03*
X709494Y399477D03*
X703500Y401290D03*
X708584Y404868D03*
X700652Y411962D03*
X705652D03*
X705177Y449384D03*
X709927Y490789D03*
X702954Y493038D03*
X701642Y484404D03*
X696652Y497444D03*
X703774Y513463D03*
X708500Y517362D03*
X708210Y537816D03*
X697018Y537577D03*
X700500Y545862D03*
X704500Y555862D03*
X710429Y545752D03*
X708056Y575081D03*
X704056Y583081D03*
X698996D03*
X702806Y613264D03*
X696928Y613207D03*
X705158Y645357D03*
X708418Y650389D03*
X699990Y752266D03*
X699247Y1508062D03*
X699140Y1513772D03*
X707050Y1531700D03*
X709150Y1536250D03*
X703290Y1551700D03*
X707050Y1548400D03*
Y1541800D03*
X703290Y1545100D03*
X708500Y1560500D03*
X699610Y1580523D03*
X708600Y1572523D03*
X710080Y1581683D03*
X710360Y1589296D03*
X702408Y1625027D03*
X709260Y1617903D03*
X705130Y1637501D03*
X707279Y1663644D03*
X714471Y46670D03*
X724621Y40062D03*
X719821Y45862D03*
X714322Y56286D03*
X714096Y73686D03*
X712717Y68541D03*
X719416Y68738D03*
Y74036D03*
X725016Y86952D03*
X720016D03*
X712341Y128093D03*
X723531Y368862D03*
X715500D03*
X717500Y401962D03*
X722613D03*
X720103Y406462D03*
X725142D03*
X714990D03*
X712702Y412200D03*
X719276Y413803D03*
X715632Y487054D03*
X725703Y492990D03*
X720652Y490354D03*
X714810Y493916D03*
X719720Y506438D03*
X716500Y521862D03*
X724500Y517362D03*
X720500Y555862D03*
X718500Y566739D03*
X719710Y612831D03*
X713343Y633842D03*
X724000Y633906D03*
X725812Y654713D03*
X715371Y654726D03*
X715923Y751112D03*
X713020Y1393361D03*
X724110Y1561825D03*
X714900Y1571273D03*
X721440Y1570963D03*
X723590Y1595323D03*
X718892Y1597152D03*
X714372Y1594679D03*
X720106Y1609542D03*
X713718Y1610235D03*
X718129Y1624330D03*
X722889Y1622491D03*
X721525Y1651863D03*
X721665Y1646221D03*
X718360Y1666203D03*
X721632Y1680658D03*
X740101Y41162D03*
X736621Y45262D03*
X733315Y40862D03*
X728721Y43562D03*
X736864Y74943D03*
X731864D03*
X739824Y91052D03*
X734380Y80518D03*
X729380D03*
X736650Y102350D03*
X735771Y94988D03*
X730660Y108484D03*
X729571Y363028D03*
X739500Y368862D03*
X731500D03*
X727500Y386862D03*
X736000Y402330D03*
X732500Y406180D03*
X728377Y402327D03*
X738100Y408780D03*
X730292Y412074D03*
X740757Y414748D03*
X730896Y478953D03*
X736200Y493000D03*
X740172Y489070D03*
X737610Y507479D03*
X732610D03*
X728610Y510479D03*
X727300Y505400D03*
X739185Y521394D03*
X728576Y537476D03*
X736500Y537862D03*
X736647Y529772D03*
X740500Y545862D03*
X738260Y553625D03*
X728714Y554190D03*
X732520Y545988D03*
X736528Y579615D03*
X729452Y576482D03*
X727253Y610689D03*
X730770Y644218D03*
X729720Y742801D03*
X729490Y752266D03*
X734371Y767152D03*
X727138Y1313090D03*
X735739Y1323048D03*
X735271Y1361408D03*
X726475Y1571293D03*
X726550Y1599358D03*
X732976Y1642878D03*
X727679Y1639962D03*
X733760Y1666906D03*
X727242Y1679913D03*
X728454Y1690491D03*
X732852Y1695701D03*
X746101Y46262D03*
X745901Y40362D03*
X747488Y71429D03*
X750701Y106642D03*
X754783Y96553D03*
X741309Y108742D03*
X743050Y139182D03*
X744911Y166887D03*
X751575Y184252D03*
X750560Y268629D03*
X748940Y313588D03*
X746522Y308804D03*
X747594Y319106D03*
X752926Y361021D03*
X755135Y368907D03*
X754813Y374362D03*
X744000Y401090D03*
X747629Y406163D03*
X754000Y403362D03*
X745929Y411963D03*
X746399Y417325D03*
X749990Y492775D03*
X743602Y493134D03*
X755317Y487157D03*
X746850Y487662D03*
X752500Y513362D03*
X753951Y521801D03*
X752965Y537678D03*
X748000Y537862D03*
X752500Y545862D03*
X751776Y564468D03*
X753483Y648749D03*
X754595Y767926D03*
X752554Y1297246D03*
X745634Y1394471D03*
X747150Y1583247D03*
X749167Y1591967D03*
X754635Y1592571D03*
X749261Y1628208D03*
X753770Y1636083D03*
X751521Y1659158D03*
X754030Y1669256D03*
X741925Y1666326D03*
X746766Y1696036D03*
X752187Y1691058D03*
X763221Y65132D03*
X757188Y91829D03*
X757576Y112575D03*
X770073Y143438D03*
X758111Y172636D03*
X762052Y274028D03*
X758510Y298620D03*
X757937Y303908D03*
Y309026D03*
X759500Y402098D03*
X767500Y401470D03*
X770246Y407458D03*
X757258Y408763D03*
X765975Y414414D03*
X769648Y430511D03*
X764446Y433726D03*
X761318Y449344D03*
X761774Y439548D03*
X766057Y451377D03*
X765393Y443989D03*
X763612Y461973D03*
X767891Y466199D03*
X762136Y455634D03*
X770590Y470940D03*
X770094Y478536D03*
X765107Y491745D03*
X769323Y494800D03*
X759555Y491548D03*
X765107Y484299D03*
X758402Y506767D03*
X764500Y513340D03*
X756800Y517050D03*
X760660Y537862D03*
X762779Y570803D03*
X760490Y752266D03*
X767557Y1328009D03*
X766455Y1360780D03*
X758163Y1506538D03*
X766950Y1581233D03*
X757610Y1584023D03*
X761510Y1638434D03*
X762030Y1668583D03*
X757557Y1684444D03*
X767381Y1676594D03*
X768463Y1687769D03*
X768733Y1694485D03*
X771356Y167518D03*
X771427Y158026D03*
X784500Y367500D03*
X775388Y390862D03*
X784498Y396353D03*
X782700Y415284D03*
X771634Y418576D03*
X771277Y413064D03*
X783256Y409340D03*
X783770Y422454D03*
X783821Y431534D03*
X775655Y439075D03*
X780877Y443344D03*
X778659Y453193D03*
X774301Y458788D03*
X783877Y475344D03*
X781541Y486817D03*
X783358Y495344D03*
X771039Y511292D03*
X777166Y504477D03*
X772100Y532700D03*
X781699Y536425D03*
X785500Y544000D03*
X773463Y563455D03*
X784217Y767666D03*
X785520Y1292160D03*
X782115Y1334173D03*
X772770Y1441270D03*
X799226Y328467D03*
X792302Y357537D03*
X795046Y363852D03*
X786571Y403455D03*
X796283Y415344D03*
Y423344D03*
X786877Y443344D03*
X796333Y439344D03*
X786887Y451344D03*
X797463Y476159D03*
X786440Y480769D03*
X786102Y507536D03*
X790503Y501826D03*
X799450Y511801D03*
X800674Y504130D03*
X798276Y531372D03*
X800500Y540500D03*
X799289Y549260D03*
X788941Y561941D03*
X792782Y565323D03*
X799742Y628983D03*
X789895Y752265D03*
X796020Y1292160D03*
X792770Y1411270D03*
Y1426270D03*
X787770Y1441270D03*
X799150Y1581379D03*
X811200Y268624D03*
X802421Y275317D03*
X802300Y284311D03*
X805509Y298850D03*
X807649Y292273D03*
X805391Y307670D03*
X812070Y341590D03*
X805425Y395502D03*
X802270Y435372D03*
X802459Y443218D03*
X802533Y449802D03*
X802752Y459344D03*
X813114Y455344D03*
X812983Y476159D03*
X801874Y471344D03*
X802752Y480159D03*
X801762Y495344D03*
X802752Y487344D03*
X805150Y623843D03*
X805421Y1321257D03*
X801614Y1339062D03*
X811771Y1355488D03*
X810150Y1574633D03*
X810050Y1584033D03*
X820901Y147112D03*
X824653Y405347D03*
X817497Y427060D03*
X816239Y435344D03*
X816117Y443552D03*
X816409Y467568D03*
X830212Y483892D03*
X827000Y489055D03*
X826552Y543612D03*
X823777Y560988D03*
X822883Y780334D03*
X822982Y791245D03*
X822494Y802941D03*
X836780Y68008D03*
X839899Y87248D03*
X841585Y94181D03*
X831298Y104206D03*
X842865Y110296D03*
X835115Y115223D03*
X845221Y135862D03*
Y129362D03*
X837161Y213207D03*
X844527Y204968D03*
X838821Y206872D03*
X837161Y218212D03*
X842539Y301629D03*
Y309306D03*
X834430Y434634D03*
X838000Y423362D03*
X838342Y514610D03*
X841660Y558200D03*
X831505Y897291D03*
X831582Y905153D03*
X844250Y1266759D03*
X838286Y1265305D03*
X837530Y1323420D03*
X833756Y1330156D03*
X840306Y1329303D03*
X833963Y1339464D03*
X838963Y1345974D03*
X841039Y1358082D03*
X839244Y1352094D03*
X841472Y1365050D03*
X850016Y87341D03*
X847473Y94754D03*
X851895Y160141D03*
X856213Y191545D03*
X847581Y232222D03*
X850328Y273557D03*
X849608Y282381D03*
X856244Y286447D03*
X860071Y304850D03*
X851517Y411745D03*
X846000Y423362D03*
X847303Y485788D03*
X849772Y494585D03*
X848097Y503315D03*
X847941Y538325D03*
X855504Y1281729D03*
X856323Y1275530D03*
X846117Y1282182D03*
X856981Y1291726D03*
X856683Y1297228D03*
X846968Y1313869D03*
X850684Y1310000D03*
X858982Y1306000D03*
X847033Y1319000D03*
X850730Y1328519D03*
X850714Y1323491D03*
X850746Y1342000D03*
X847032Y1337388D03*
X847016Y1332041D03*
X850762Y1347090D03*
X852050Y1584033D03*
X874295Y163862D03*
X863488Y176332D03*
X875170Y185113D03*
X867529Y231788D03*
X863104Y273103D03*
X868104D03*
X867701Y267537D03*
X863230Y280001D03*
X866619Y286801D03*
X871099Y323000D03*
X863420Y429362D03*
X860541Y446089D03*
X864361Y493001D03*
X866727Y650739D03*
X870591Y785437D03*
X865394Y801244D03*
X867651Y836820D03*
X865109Y850795D03*
X864768Y844815D03*
X864140Y856052D03*
X864003Y866609D03*
X869638Y1299044D03*
X861020Y1314500D03*
X865337Y1311852D03*
X863827Y1304213D03*
X861757Y1319500D03*
X865000Y1328500D03*
Y1323500D03*
X862498Y1346000D03*
X865333Y1341324D03*
X861000Y1337500D03*
Y1332500D03*
X874989Y1410441D03*
X863745Y1444560D03*
X889351Y195489D03*
X878221Y192055D03*
X881354Y267407D03*
X885764Y284361D03*
X877448Y284825D03*
X888000Y293000D03*
X884410Y794332D03*
X876923Y1239520D03*
X886707Y1235920D03*
X886145Y1270835D03*
X886647Y1299183D03*
X883379Y1417881D03*
X881987Y1449608D03*
X887519Y1444625D03*
X877226Y1441585D03*
X902376Y590172D03*
X903556Y614062D03*
X903941Y893000D03*
X903925Y948500D03*
X900280Y1150769D03*
X896225Y1140635D03*
X891247Y1219520D03*
X896974Y1229869D03*
X892724Y1270516D03*
X893875Y1276116D03*
Y1281216D03*
Y1286316D03*
X893506Y1296599D03*
X893875Y1291316D03*
X900875Y1311355D03*
X898395Y1306920D03*
X903292Y1315822D03*
X904023Y1320892D03*
X900891Y1324898D03*
Y1330005D03*
X900890Y1342808D03*
X896866Y1346000D03*
X904224Y1333843D03*
X900922Y1337725D03*
X894050Y1584033D03*
X894150Y1602633D03*
X917387Y184114D03*
X914575Y560027D03*
X913845Y846656D03*
X907011Y849556D03*
X910500Y863500D03*
X905500D03*
X915000Y893000D03*
Y898000D03*
X909010Y919000D03*
X912425Y941500D03*
X907000D03*
X915575Y948500D03*
X912500Y963309D03*
X907500D03*
X909000Y974000D03*
Y982000D03*
X919779Y1155658D03*
X912053Y1225520D03*
X910707Y1235920D03*
X919691Y1268440D03*
X919725Y1276362D03*
X919128Y1285953D03*
X919721Y1291676D03*
X919784Y1296984D03*
X916415Y1310000D03*
X912371Y1313885D03*
X912387Y1319000D03*
X908892Y1322803D03*
X908894Y1328000D03*
X908889Y1341343D03*
X908912Y1346419D03*
X912211Y1332473D03*
X912222Y1337513D03*
X922128Y182486D03*
X923386Y193563D03*
X920031Y577846D03*
X926449Y577806D03*
X926983Y604751D03*
X920989Y617692D03*
X930926Y664791D03*
X920234Y843349D03*
X927777Y843416D03*
X934129Y844500D03*
X928000Y893000D03*
Y898000D03*
X934500Y926500D03*
X929500D03*
X928500Y941500D03*
X923500D03*
X928500Y956339D03*
X923500Y956304D03*
X927000Y982500D03*
Y977500D03*
X930657Y1103041D03*
X920107Y1229920D03*
X931085Y1268500D03*
X931284Y1276841D03*
X931506Y1285085D03*
X928718Y1300098D03*
X931708Y1293994D03*
X928219Y1308085D03*
X922000Y1324000D03*
X931326Y1328467D03*
X931216Y1323050D03*
X925500Y1333000D03*
X930411Y1347411D03*
X931798Y1670937D03*
X923798D03*
X936454Y184015D03*
X937267Y189010D03*
X945120Y193264D03*
X949181Y280131D03*
X937310Y580755D03*
X939511Y597073D03*
X935746Y611573D03*
X935783Y631192D03*
X945602Y664653D03*
X939216Y664767D03*
X948644Y811190D03*
X941033Y846608D03*
X948000Y862000D03*
X938000Y862620D03*
X943000Y862823D03*
X942500Y926500D03*
X942631Y943162D03*
X936960Y942898D03*
X947207Y979322D03*
X937148Y1134343D03*
X947305Y1150769D03*
X943431Y1140700D03*
X946101Y1219520D03*
X935907Y1239520D03*
X945691Y1235920D03*
X947054Y1268260D03*
X935028Y1313769D03*
X949216Y1448337D03*
X944105Y1448317D03*
X947798Y1670937D03*
X939798D03*
X952798Y165945D03*
X960419Y162294D03*
X952158Y174590D03*
X961407Y205125D03*
X951102Y628662D03*
X951886Y804495D03*
X951466Y816400D03*
X963134Y864000D03*
X956500Y893000D03*
X961500D03*
X950500Y926500D03*
X955865Y983816D03*
X955758Y1144718D03*
X955958Y1229869D03*
X964669Y1271000D03*
X964454Y1287396D03*
X955372Y1311500D03*
X958500Y1306500D03*
X953516Y1305500D03*
X950872Y1314500D03*
Y1319500D03*
X955372Y1328500D03*
Y1323500D03*
X954872Y1346500D03*
Y1341500D03*
X951372Y1337500D03*
Y1332500D03*
X954541Y1448307D03*
X961566Y1448341D03*
X963402Y1501204D03*
X958402D03*
X959584Y1550824D03*
X964774Y173053D03*
X966907Y1225520D03*
X969691Y1235920D03*
X979091Y1229920D03*
X968823Y1267000D03*
X978126Y1268528D03*
X966569Y1282182D03*
X974391Y1295098D03*
X969519Y1452784D03*
X973255Y1456714D03*
X990579Y155248D03*
X988751Y167541D03*
X986447Y158209D03*
X989605Y175400D03*
X985922Y171861D03*
X982455Y260781D03*
Y271443D03*
X984509Y303623D03*
X988460Y358405D03*
X993460D03*
X992460Y370659D03*
X985668Y389311D03*
X980690Y387784D03*
X993650Y465315D03*
X988650D03*
X991270Y470212D03*
X988125Y485193D03*
X994056Y521014D03*
Y516014D03*
Y526074D03*
Y531074D03*
X982665Y1265474D03*
X991823Y1312005D03*
X991500Y1323500D03*
X992000Y1331000D03*
X993500Y1339370D03*
X980779Y1451545D03*
X981768Y1501204D03*
X991196Y1550840D03*
X1002736Y157943D03*
X995181Y157689D03*
X996416Y176579D03*
X1002921Y178799D03*
X1002827Y172479D03*
X1008918Y192994D03*
X1008121Y203525D03*
X1005641Y214969D03*
X997300Y234876D03*
X1006468Y301857D03*
X1003460Y358405D03*
X998460D03*
X1000460Y369535D03*
X996889Y374156D03*
X998359Y451675D03*
X1003909Y454662D03*
Y460162D03*
X996320Y470364D03*
X1002056Y521014D03*
Y516014D03*
Y526074D03*
Y531074D03*
X1002055Y1272690D03*
X1006148Y1283493D03*
X1004483Y1294268D03*
X996988Y1312462D03*
X996848Y1304602D03*
X996000Y1318500D03*
X996500Y1326050D03*
X996000Y1343790D03*
X996500Y1334950D03*
X995936Y1349064D03*
X995000Y1362000D03*
X1005134Y1501204D03*
X1023221Y191574D03*
X1011120Y198114D03*
X1017361Y203109D03*
X1011068Y207667D03*
X1019356Y222423D03*
X1010909Y213708D03*
X1011721Y233699D03*
X1023110Y287311D03*
X1023000Y298311D03*
X1009815Y404896D03*
X1020748Y420902D03*
X1023420Y462921D03*
X1017220Y464155D03*
X1023515Y454397D03*
X1019205Y457687D03*
X1023420Y468039D03*
X1017350Y472155D03*
X1022874Y474545D03*
X1019210Y480155D03*
X1013306Y532501D03*
X1019161Y554757D03*
X1024161D03*
X1017961Y545074D03*
X1014666Y1294268D03*
X1009905Y1305500D03*
X1012500Y1322500D03*
Y1341580D03*
X1013500Y1332740D03*
X1016000Y1361000D03*
X1012500Y1347500D03*
X1022796Y1550840D03*
X1034214Y351601D03*
X1034409Y429618D03*
X1024509Y500168D03*
X1037254Y521014D03*
X1036708Y514883D03*
X1037254Y526074D03*
X1025631Y540104D03*
X1036021Y534990D03*
X1030000Y554500D03*
X1028500Y563000D03*
X1038801Y751765D03*
X1036427Y770532D03*
X1038867Y774960D03*
X1028500Y1501204D03*
X1042015Y444404D03*
X1043991Y540979D03*
X1039407Y547723D03*
X1042628Y556845D03*
X1048684Y1340304D03*
X1051866Y1501204D03*
X1050866Y1659548D03*
X1053290Y1652082D03*
X1045545Y1663089D03*
X1055934Y388988D03*
X1068143Y380188D03*
X1055934Y381988D03*
X1062640Y449155D03*
X1057276Y458155D03*
X1062173Y479655D03*
X1062250Y484672D03*
X1056960Y482262D03*
X1058231Y523238D03*
X1060719Y512359D03*
X1068801Y751765D03*
X1063470Y767665D03*
X1063684Y1340304D03*
X1054396Y1550840D03*
X1063751Y1653834D03*
X1068221Y1662778D03*
X1071698Y270702D03*
X1078400Y391226D03*
X1074654Y380188D03*
X1074249Y387795D03*
X1082866Y403068D03*
X1072738Y411322D03*
Y416763D03*
Y421922D03*
X1077873Y463444D03*
X1071710Y483655D03*
Y488782D03*
X1072232Y667749D03*
X1077034Y1375927D03*
X1075232Y1501204D03*
X1086714Y353515D03*
X1090061Y428019D03*
X1084840Y438234D03*
Y443515D03*
Y460005D03*
X1085851Y465978D03*
X1096473Y484391D03*
Y489391D03*
X1095730Y509362D03*
X1098301Y752265D03*
X1093116Y766369D03*
X1086801Y1297382D03*
X1089934Y1550784D03*
X1097000Y1629500D03*
X1096469Y1643468D03*
X1096768Y1635080D03*
X1087141Y1688914D03*
X1089030Y1717841D03*
Y1722841D03*
X1107300Y456944D03*
X1111076Y464388D03*
X1108076Y646774D03*
X1109634Y1375927D03*
X1099098Y1501204D03*
X1102248Y1496186D03*
X1111701Y1558640D03*
X1100961Y1622543D03*
X1105000Y1682132D03*
X1099108Y1691229D03*
X1121628Y401915D03*
X1121077Y511498D03*
X1120321Y635832D03*
X1127801Y752265D03*
X1122728Y765651D03*
X1119067Y1551457D03*
X1115394Y1620306D03*
X1116000Y1671029D03*
X1122610Y1677976D03*
X1124091Y1683983D03*
X1113948Y1711244D03*
X1142830Y53186D03*
X1142144Y63186D03*
X1129387Y615658D03*
X1138387D03*
X1136301Y1297382D03*
X1142334Y1375927D03*
X1142639Y1562789D03*
X1138480Y1576364D03*
X1132168Y1620860D03*
X1132981Y1634531D03*
X1132209Y1672033D03*
X1151679Y72258D03*
X1157301Y752265D03*
X1145819Y1348254D03*
X1147814Y1562823D03*
X1154336Y1555979D03*
X1149278Y1589453D03*
X1158343Y1658514D03*
X1151985Y1666685D03*
X1152114Y1672517D03*
X1152211Y1682373D03*
X1168687Y74202D03*
X1158764Y489516D03*
X1162067Y570050D03*
X1163485Y1546195D03*
X1161492Y1551175D03*
X1172523Y1573250D03*
X1165806Y1658934D03*
X1159688Y1665427D03*
X1169098Y1666278D03*
X1167228Y1671116D03*
X1169187Y1687117D03*
X1167247Y1680845D03*
X1183354Y77685D03*
X1185913Y93634D03*
X1174031Y403519D03*
X1181000Y402500D03*
X1185952Y432202D03*
Y440202D03*
Y448202D03*
X1178340Y447734D03*
X1185707Y465272D03*
X1186040Y481691D03*
X1182950Y577030D03*
X1178000Y572602D03*
X1182594Y587759D03*
X1178000Y592673D03*
X1182256Y632368D03*
X1188301Y752265D03*
X1185001Y1297382D03*
X1175234Y1375927D03*
X1182305Y1539640D03*
X1184138Y1548524D03*
X1182503Y1555540D03*
X1180087Y1575871D03*
X1178932Y1686698D03*
X1182548Y1679649D03*
Y1674649D03*
X1185676Y1697249D03*
X1198694Y57015D03*
X1191488Y87125D03*
X1200518Y100875D03*
X1200037Y160987D03*
X1189701Y173187D03*
X1201157Y431875D03*
X1193040Y481691D03*
X1199370Y578154D03*
X1195236Y581407D03*
X1195336Y586606D03*
X1191714Y767265D03*
X1194296Y1396500D03*
X1203242Y1417440D03*
X1202548Y1407453D03*
X1202857Y1412454D03*
X1202411Y1427410D03*
X1203117Y1422452D03*
X1202475Y1432468D03*
X1203040Y1437500D03*
X1194000Y1442500D03*
X1190755Y1588978D03*
X1189989Y1605260D03*
X1197980Y1688270D03*
X1189263Y1682551D03*
X1190830Y1675710D03*
X1189462Y1691366D03*
X1197612Y1703334D03*
X1192612D03*
X1196767Y1712261D03*
X1199294Y1721143D03*
X1196814Y1726261D03*
X1208431Y128748D03*
X1215528Y172395D03*
X1214094Y269008D03*
X1213866Y455376D03*
X1208733Y585986D03*
X1204334Y668138D03*
X1210111Y1249357D03*
X1207801Y1348525D03*
X1208034Y1375927D03*
X1211555Y1380511D03*
X1210400Y1440000D03*
X1209721Y1591140D03*
X1207823Y1673581D03*
X1207750Y1688514D03*
X1211135Y1680846D03*
X1212547Y1675898D03*
X1212954Y1703343D03*
X1207954D03*
X1207770Y1717011D03*
X1223455Y91346D03*
X1227803Y94210D03*
X1221411Y134230D03*
X1221512Y128239D03*
X1231118Y142125D03*
X1230094Y269008D03*
X1222094D03*
X1230694Y302716D03*
Y308566D03*
X1218430Y421012D03*
X1221075Y668115D03*
X1229934Y785057D03*
X1230177Y801163D03*
X1228800Y1391300D03*
X1219650Y1392050D03*
X1219500Y1398900D03*
Y1436000D03*
X1220200Y1449100D03*
X1231575Y1579740D03*
X1224170Y1670050D03*
X1219738Y1713861D03*
Y1708861D03*
Y1722861D03*
Y1727861D03*
X1239218Y128239D03*
Y137239D03*
X1247834Y159844D03*
X1246094Y269008D03*
X1238094D03*
X1247785Y295357D03*
X1233468Y419742D03*
X1242429Y443255D03*
X1242692Y483435D03*
X1235177Y788813D03*
X1240177Y801163D03*
X1235177D03*
X1246025Y1329781D03*
X1235400Y1391200D03*
X1238500Y1400900D03*
X1234900Y1404400D03*
X1238200Y1395500D03*
X1235679Y1418908D03*
X1239426Y1591768D03*
X1249152Y72895D03*
X1256064Y101100D03*
X1249065Y241594D03*
Y236594D03*
Y251594D03*
Y246594D03*
X1262094Y269008D03*
X1254094D03*
X1260107Y399125D03*
X1260227Y411128D03*
X1256137Y459182D03*
Y453872D03*
X1248902Y470733D03*
X1257016Y467253D03*
X1275981Y85114D03*
X1269146Y121022D03*
X1263146D03*
X1267037Y180565D03*
X1270094Y269008D03*
X1275585Y393597D03*
X1269840Y411128D03*
X1276980Y1540540D03*
X1272570Y1550910D03*
X1273020Y1545050D03*
X1271640Y1591001D03*
X1263772Y1661154D03*
X1276641D03*
X1287486Y134165D03*
X1278137Y171551D03*
Y184987D03*
X1279447Y213292D03*
X1278094Y269008D03*
X1286094D03*
X1289352Y421950D03*
X1279352Y782824D03*
Y787824D03*
X1281290Y1243712D03*
X1278921Y1329753D03*
X1279525Y1432000D03*
X1287700Y1431700D03*
X1299196Y76209D03*
X1305685Y74748D03*
X1300668Y125739D03*
X1306431Y149330D03*
X1300668Y145739D03*
X1294094Y269008D03*
X1302094D03*
X1304594Y308475D03*
X1293277Y401125D03*
X1296228Y408125D03*
X1302500Y664500D03*
X1294448Y801088D03*
X1299448D03*
X1296000Y1427700D03*
X1301900D03*
X1295700Y1421800D03*
X1300800D03*
X1302390Y1530430D03*
X1295869Y1586934D03*
X1300214Y1662888D03*
X1319667Y87587D03*
Y105227D03*
X1310094Y269008D03*
X1318094D03*
X1316934Y298184D03*
Y303184D03*
X1316266Y564514D03*
X1314194Y1243712D03*
X1311825Y1329696D03*
X1308900Y1525510D03*
X1311767Y1541989D03*
X1311242Y1553193D03*
X1313021Y1548299D03*
X1312700Y1579596D03*
X1319349Y1585567D03*
X1309510Y1588851D03*
X1312014Y1661157D03*
X1327541Y105227D03*
X1337399Y98084D03*
X1326094Y269008D03*
X1334094D03*
X1330820Y525165D03*
Y518265D03*
X1330658Y538749D03*
X1329585Y561806D03*
X1336938Y646221D03*
Y661221D03*
X1337304Y1225023D03*
X1329507Y1228559D03*
X1324293Y1591500D03*
X1323864Y1661179D03*
X1337033Y1661129D03*
X1330473D03*
X1351750Y72826D03*
X1339840Y72860D03*
X1344958Y85358D03*
X1342094Y269008D03*
X1350094D03*
X1346690Y1243769D03*
X1344625Y1329896D03*
X1350188Y1579740D03*
X1344165Y1593174D03*
X1347966Y1661155D03*
X1361550Y67264D03*
X1356868Y85324D03*
X1364369Y120380D03*
X1358094Y269008D03*
X1366094D03*
X1352727Y1214064D03*
X1356196Y1217750D03*
X1369808Y87587D03*
X1377682D03*
X1371259Y98000D03*
X1373862Y511052D03*
X1381457Y511050D03*
X1382123Y614130D03*
X1376312Y623505D03*
X1379438Y646221D03*
X1374261Y709651D03*
X1377207Y1349227D03*
X1369119Y1579775D03*
X1382045Y1700038D03*
X1383715Y236594D03*
Y241594D03*
X1386839Y1595126D03*
X1390102Y1645070D03*
X1385068Y1664907D03*
X1390738Y1664938D03*
X1390179Y1733118D03*
X1411000Y460362D03*
X1409012Y656405D03*
X1406667Y742523D03*
X1405570Y1540510D03*
X1400650Y1550940D03*
X1401200Y1544920D03*
X1403232Y1579519D03*
X1404132Y1588850D03*
X1409286Y1605796D03*
X1400029Y1615796D03*
X1406447Y1619572D03*
X1417000Y460362D03*
X1414823Y647030D03*
X1414157Y670665D03*
X1416289Y1190574D03*
X1422037Y1192848D03*
X1416529Y1313100D03*
X1416327Y1362279D03*
X1411989Y1371140D03*
X1413629Y1393578D03*
X1416862Y1582871D03*
X1419811Y1599084D03*
X1416709Y1592819D03*
X1413836Y1586944D03*
X1418000Y1607500D03*
X1421392Y1621706D03*
X1415622Y1631013D03*
X1421890Y1635500D03*
X1418755Y1654999D03*
X1431262Y61392D03*
X1441612Y688985D03*
X1441757Y775133D03*
X1440714Y841401D03*
X1439586Y1193581D03*
X1426989Y1391140D03*
X1435584Y1596545D03*
X1431981Y1586934D03*
X1438565Y1612583D03*
X1430319Y1623504D03*
X1430238Y1617137D03*
X1429072Y1643655D03*
X1433618Y1659331D03*
X1433157Y1651977D03*
X1438078Y1669992D03*
X1439316Y1675080D03*
X1454769Y163842D03*
X1449769Y174217D03*
X1456500Y457000D03*
X1453564Y537856D03*
X1453177Y563178D03*
X1447423Y679610D03*
X1446757Y703265D03*
X1451352Y848315D03*
X1456352D03*
X1454947Y1193428D03*
X1442045Y1200597D03*
X1448097Y1541990D03*
X1447354Y1553193D03*
X1449133Y1548299D03*
X1447026Y1577299D03*
X1455461Y1585567D03*
X1455312Y1593035D03*
X1455579Y1665701D03*
X1454705Y1671267D03*
X1449551Y1665923D03*
X1466681Y78590D03*
X1462682Y450372D03*
X1456982Y437362D03*
X1461832Y584268D03*
X1465257Y1193188D03*
X1460011Y1196750D03*
X1468357Y1198458D03*
X1463041Y1201640D03*
X1472129Y56083D03*
X1473362Y558380D03*
X1473593Y567449D03*
X1481898Y585476D03*
X1477253Y575751D03*
X1472935Y578344D03*
X1473234Y572437D03*
X1474530Y708562D03*
X1479757Y722865D03*
X1480677Y813488D03*
X1483177Y1193001D03*
X1475597Y1192758D03*
X1480466Y1200046D03*
X1472046Y1592895D03*
X1476416Y1688959D03*
X1486000Y1686000D03*
X1482987Y1690453D03*
X1497386Y464980D03*
X1495682Y473302D03*
X1492514Y539657D03*
X1488510Y542816D03*
X1487660Y585748D03*
X1500500Y809063D03*
X1498177Y829359D03*
X1493821Y1203172D03*
X1495749Y1579740D03*
X1491709Y1593453D03*
X1495874Y1664210D03*
X1488875Y1677385D03*
X1491300Y1730212D03*
X1514576Y219730D03*
X1506865Y546462D03*
X1507644Y554372D03*
X1507468Y564357D03*
X1509757Y575477D03*
X1501821Y577664D03*
X1507612Y708562D03*
X1512757Y722897D03*
X1505287Y789710D03*
X1516114Y1593174D03*
X1529384Y201245D03*
X1519120Y479215D03*
X1527853Y560264D03*
X1518677Y798188D03*
X1523177Y800988D03*
X1527542Y1244837D03*
X1536422Y292816D03*
X1536542Y304819D03*
X1534584Y467067D03*
X1539693Y543613D03*
X1532824Y555981D03*
X1539693Y558943D03*
X1540412Y708562D03*
X1535852Y796138D03*
Y801138D03*
X1543503Y1269314D03*
X1542700Y1540600D03*
X1536770Y1550990D03*
X1537270Y1545020D03*
X1539344Y1579519D03*
X1536893Y1593593D03*
X1556960Y287478D03*
X1551900Y287288D03*
X1548772Y291916D03*
X1551779Y530698D03*
X1546257Y701097D03*
X1556708Y772782D03*
X1553644Y796544D03*
X1560033Y796421D03*
X1548393Y798093D03*
X1551113Y1238088D03*
X1555803Y1276353D03*
X1555852Y1282988D03*
X1560454Y1279004D03*
X1548544Y1297145D03*
X1555222Y1302757D03*
X1557557Y1550574D03*
X1557690Y1542662D03*
X1560043Y1586934D03*
X1569592Y294816D03*
X1572283Y301816D03*
X1564506Y310334D03*
X1572436Y582433D03*
Y574022D03*
X1564785Y611416D03*
X1572759Y611471D03*
X1573749Y686829D03*
X1572588Y762782D03*
X1572182Y792552D03*
X1564553Y801152D03*
X1567737Y1271411D03*
X1569865Y1293656D03*
X1568456Y1311533D03*
X1572416Y1303160D03*
X1564268Y1338440D03*
X1572331Y1348205D03*
X1570040Y1352702D03*
X1561348Y1547217D03*
X1575734Y1541990D03*
X1575416Y1553193D03*
X1574966Y1577038D03*
X1589778Y611456D03*
X1580861Y611440D03*
X1576843Y674425D03*
X1578069Y1256036D03*
X1577630Y1264418D03*
X1584069Y1279706D03*
X1585290Y1285098D03*
X1586110Y1312941D03*
X1580987Y1316110D03*
X1576554Y1338769D03*
X1584156Y1381419D03*
X1586000Y1387641D03*
X1590723Y1381589D03*
X1577195Y1548299D03*
X1583523Y1585567D03*
X1576568Y1590873D03*
X1603970Y222956D03*
X1599837Y295328D03*
X1604890Y531226D03*
X1596299Y536344D03*
X1605618Y731512D03*
X1592188Y739012D03*
X1595355Y792409D03*
X1593237Y1244182D03*
X1595827Y1252679D03*
X1590921Y1309276D03*
X1597621Y1365384D03*
X1592788Y1388318D03*
X1597234Y1382689D03*
X1595046Y1592825D03*
X1619909Y298742D03*
Y293742D03*
X1616198Y556364D03*
X1618859Y542820D03*
X1607369Y561330D03*
X1618356Y609137D03*
X1606312Y652853D03*
X1616801Y752265D03*
X1612597Y1284510D03*
X1629597Y221842D03*
X1631657Y392925D03*
X1622391Y564169D03*
X1635281Y1422450D03*
X1635227Y1436528D03*
X1623811Y1579740D03*
X1623634Y1593871D03*
X1642135Y414202D03*
X1647110Y434177D03*
X1635944Y609510D03*
X1645123Y624478D03*
X1639312Y633853D03*
X1638377Y714972D03*
X1646301Y752265D03*
X1647072Y1323137D03*
X1644001Y1408069D03*
X1646483Y1412741D03*
X1635619Y1430536D03*
X1639834Y1434478D03*
X1636167Y1446746D03*
X1642400Y1439674D03*
X1650400Y1437820D03*
X1641167Y1446746D03*
X1648337Y1451313D03*
X1643158Y1593313D03*
X1645343Y1667718D03*
X1645029Y1715609D03*
Y1710609D03*
Y1725759D03*
Y1730759D03*
X1652525Y141762D03*
X1661110Y389177D03*
Y404177D03*
Y419177D03*
Y434177D03*
X1654110D03*
X1657194Y599956D03*
X1651194D03*
X1657194Y609450D03*
X1651194D03*
X1654147Y616523D03*
X1661017Y670128D03*
X1661317Y689093D03*
X1661007Y700243D03*
X1651214Y765725D03*
X1651301Y1363765D03*
X1660585Y1393660D03*
X1661807Y1416948D03*
X1663777Y1421568D03*
X1658345Y1423124D03*
X1653380Y1657850D03*
X1656101Y1671720D03*
X1651101Y1671833D03*
X1657125Y1661895D03*
X1651698Y1665045D03*
X1653984Y1687051D03*
X1653964Y1676449D03*
X1656101Y1701094D03*
X1673100Y121762D03*
Y136762D03*
X1676110Y389177D03*
Y404177D03*
Y419177D03*
Y434177D03*
X1668516Y599956D03*
X1674516D03*
X1668516Y609450D03*
X1674516D03*
X1676017Y670128D03*
X1676801Y752265D03*
X1670972Y1322837D03*
X1669410Y1421971D03*
X1671079Y1435069D03*
X1666985Y1429651D03*
X1676685Y1537893D03*
X1668027Y1541216D03*
X1671034Y1546934D03*
X1677988Y1561649D03*
X1665750Y1587875D03*
X1676971Y1668582D03*
X1670202Y1663150D03*
X1675290Y1663157D03*
X1668481Y1686259D03*
X1668257Y1679992D03*
X1680029Y1710609D03*
Y1715609D03*
X1670417Y1718373D03*
X1695100Y121762D03*
Y136762D03*
Y131762D03*
Y146762D03*
Y156762D03*
Y161762D03*
Y166762D03*
X1682408Y228337D03*
X1692429Y403985D03*
X1694050Y416643D03*
X1690208Y421855D03*
X1692450Y436772D03*
X1689892Y751674D03*
X1680974Y765871D03*
X1695072Y1322737D03*
X1693367Y1393760D03*
X1681538Y1451522D03*
X1689062Y1451496D03*
X1684172Y1538135D03*
X1686675Y1659287D03*
X1680367Y1663367D03*
X1684733Y1698952D03*
X1695102Y1698947D03*
X1689184Y1702095D03*
X1680877Y1723593D03*
X1702959Y404243D03*
X1697161Y406602D03*
X1707780Y410738D03*
X1695455Y422287D03*
X1707568Y420370D03*
X1701124Y423802D03*
X1707544Y431745D03*
X1699500Y654738D03*
Y673738D03*
X1705801Y752265D03*
X1700868Y766098D03*
X1706850Y1468146D03*
X1709964Y1597490D03*
X1709833Y1612940D03*
Y1606340D03*
X1701984Y1671618D03*
X1695987D03*
X1717148Y19910D03*
X1722085Y25908D03*
X1717055D03*
X1723241Y48822D03*
X1724602Y40966D03*
X1721646Y68115D03*
X1716558Y67866D03*
X1712686Y111908D03*
X1713399Y132858D03*
X1718465Y657982D03*
X1720050Y649142D03*
X1716030Y668182D03*
X1718686Y676154D03*
X1718425Y1468245D03*
X1715693Y1597190D03*
X1719893Y1612940D03*
Y1603040D03*
X1713593Y1609640D03*
Y1603040D03*
X1710170Y1718963D03*
X1719181Y1706712D03*
X1721172Y1712115D03*
X1719218Y1727265D03*
X1719148Y1721530D03*
X1739492Y48971D03*
X1731743Y45001D03*
X1739876Y40742D03*
X1728965Y112941D03*
X1729046Y118178D03*
X1739686Y120938D03*
X1725344Y359334D03*
X1733043Y657091D03*
X1736848Y650974D03*
X1737002Y671494D03*
X1734801Y752265D03*
X1730912Y766977D03*
X1739188Y1478171D03*
X1733065Y1543771D03*
X1726604Y1540970D03*
X1736479Y1584330D03*
X1735463Y1651965D03*
X1730381Y1647386D03*
X1734500Y1656965D03*
X1734962Y1662965D03*
X1734963Y1673465D03*
X1734763Y1680465D03*
X1739315Y1677444D03*
X1731936Y1690165D03*
X1732251Y1708265D03*
X1748708Y26641D03*
X1751031Y39063D03*
X1743491Y92827D03*
X1748686Y97408D03*
X1750786Y120018D03*
X1744976Y122998D03*
X1754339Y128242D03*
X1749169Y206849D03*
X1744510Y377452D03*
X1744380Y382892D03*
X1742306Y661032D03*
X1748062Y1298189D03*
Y1328189D03*
Y1358189D03*
X1743179Y1563578D03*
X1746779Y1583378D03*
X1751558Y1579332D03*
X1750463Y1654465D03*
X1744963Y1656465D03*
X1744463Y1651229D03*
X1751340Y1686140D03*
X1744620Y1716018D03*
X1747120Y1710824D03*
X1765920Y17031D03*
Y22031D03*
X1767266Y48748D03*
X1765527Y53692D03*
X1767956Y76843D03*
X1767136Y83653D03*
X1764644Y122973D03*
X1756606Y228938D03*
X1768041Y556537D03*
X1765301Y752265D03*
X1760246Y767468D03*
X1759388Y1478171D03*
X1769054Y1585705D03*
X1755463Y1654465D03*
X1767888Y1664465D03*
X1765163Y1670543D03*
X1765463Y1677465D03*
X1761463Y1683465D03*
X1770920Y17031D03*
Y22031D03*
X1775920D03*
X1773830Y49000D03*
X1779377Y50738D03*
X1775546Y73376D03*
X1781451Y88238D03*
X1773577Y88339D03*
X1776930Y179051D03*
X1771606Y228938D03*
Y243938D03*
X1770520Y364148D03*
X1782376Y558324D03*
X1783388Y1478171D03*
X1780579Y1582178D03*
X1776785Y1573879D03*
X1787826Y37548D03*
X1792546Y59443D03*
Y74443D03*
X1785108Y76078D03*
X1792546Y89443D03*
X1787756Y85178D03*
X1787390Y156834D03*
X1785320Y193072D03*
X1784915Y186053D03*
X1786606Y228938D03*
Y243938D03*
X1789771Y367866D03*
X1797929Y385293D03*
X1786260Y379059D03*
X1792507Y403932D03*
X1792335Y418775D03*
X1792450Y410615D03*
X1792220Y425432D03*
X1788376Y558324D03*
X1807546Y59443D03*
X1800046Y66943D03*
Y81943D03*
Y96943D03*
X1809595Y180781D03*
X1806470Y186866D03*
X1811274Y198098D03*
X1808429Y218837D03*
X1811606Y226438D03*
X1801606Y243938D03*
X1803129Y362293D03*
X1802929Y385293D03*
X1807388Y1478171D03*
X1818828Y175241D03*
X1817275Y180619D03*
X1816190Y208879D03*
X1816606Y243938D03*
X1819260Y295460D03*
X1820307Y373829D03*
X1828669Y379552D03*
X1820656Y388051D03*
X1820144Y398052D03*
X1819374Y410432D03*
X1818874Y423932D03*
X1822394Y436225D03*
X1828888Y1478171D03*
X1829732Y371329D03*
G54D22*
X38812Y547005D03*
X46292D03*
X272844Y1514077D03*
X280324D03*
X400906D03*
X408386D03*
X537571Y170765D03*
X545051D03*
X537017Y1514077D03*
X544497D03*
X553480Y131793D03*
X560960D03*
X1280717Y1547077D03*
X1288197D03*
X1408779D03*
X1416259D03*
X1544891D03*
X1552371D03*
G54D106*
X912209Y869555D03*
X903941D03*
X912209Y886681D03*
X903941D03*
X935789Y869792D03*
X944057D03*
X935789Y886918D03*
X944057D03*
X954866Y869937D03*
Y887063D03*
X963134Y869937D03*
Y887063D03*
G54D124*
X1766929Y1714960D03*
G54D40*
X187673Y1656735D03*
X195153D03*
X187673Y1671753D03*
X195153D03*
X187673Y1659294D03*
X195153Y1661853D03*
Y1659294D03*
X187673Y1661853D03*
Y1674312D03*
X195153Y1676871D03*
Y1674312D03*
X187673Y1676871D03*
X187820Y1686870D03*
Y1689429D03*
X195300Y1686870D03*
Y1691988D03*
Y1689429D03*
X187820Y1691988D03*
Y1701988D03*
Y1704547D03*
X195300Y1701988D03*
Y1707106D03*
Y1704547D03*
X187820Y1707106D03*
X394186Y1670218D03*
Y1675336D03*
Y1672777D03*
X401666Y1670218D03*
Y1672777D03*
Y1675336D03*
X444760Y1641441D03*
X452240D03*
X444760Y1646559D03*
Y1644000D03*
X452240D03*
Y1646559D03*
X663198Y1700695D03*
Y1698136D03*
X655718Y1700695D03*
Y1695577D03*
Y1698136D03*
X663198Y1695577D03*
Y1714695D03*
Y1712136D03*
X655718Y1714695D03*
Y1709577D03*
Y1712136D03*
X663198Y1709577D03*
X1209176Y292066D03*
Y289507D03*
Y286948D03*
X1225176Y292066D03*
Y289507D03*
Y286948D03*
X1216656D03*
Y289507D03*
Y292066D03*
X1243325Y300157D03*
X1235845D03*
X1232656Y286948D03*
Y289507D03*
Y292066D03*
X1243325Y302716D03*
Y305275D03*
X1235845D03*
Y302716D03*
X1257176Y292066D03*
Y289507D03*
Y286948D03*
X1273176Y292066D03*
Y289507D03*
Y286948D03*
X1264656D03*
Y289507D03*
Y292066D03*
X1289176D03*
Y289507D03*
Y286948D03*
X1280656D03*
Y289507D03*
Y292066D03*
X1304594Y298066D03*
X1296656Y286948D03*
Y289507D03*
Y292066D03*
X1304594Y303184D03*
Y300625D03*
X1305176Y292066D03*
Y289507D03*
Y286948D03*
X1312656D03*
Y289507D03*
Y292066D03*
X1312074Y298066D03*
Y300625D03*
Y303184D03*
X1329176Y292066D03*
Y289507D03*
Y286948D03*
X1345176Y292066D03*
Y289507D03*
Y286948D03*
X1336656D03*
Y289507D03*
Y292066D03*
X1361176D03*
Y289507D03*
Y286948D03*
X1352656D03*
Y289507D03*
Y292066D03*
X1368656Y286948D03*
Y289507D03*
Y292066D03*
X1394945Y1641681D03*
X1402425D03*
X1394945Y1644240D03*
X1402425Y1646799D03*
Y1644240D03*
X1394945Y1646799D03*
X1705370Y1718475D03*
Y1721034D03*
Y1723593D03*
X1697890D03*
Y1721034D03*
Y1718475D03*
G54D13*
X26181Y1457243D03*
Y1482439D03*
X50081Y1457243D03*
Y1482439D03*
X56458Y1497397D03*
Y1522593D03*
X74181Y1457243D03*
Y1482439D03*
X96081Y1457243D03*
Y1482439D03*
X91477Y1497397D03*
Y1522593D03*
X111794Y1325453D03*
Y1350649D03*
X147894Y1325653D03*
Y1350849D03*
X208994Y1325553D03*
Y1350749D03*
X277561Y1279707D03*
Y1304903D03*
X288381Y713164D03*
Y738360D03*
X306983Y1279707D03*
Y1304903D03*
X326951Y733314D03*
Y758510D03*
X341576Y1279622D03*
Y1304818D03*
X356657Y733314D03*
Y758510D03*
X375976Y1279597D03*
Y1304793D03*
X387151Y733280D03*
Y758476D03*
X410661Y1298921D03*
Y1324117D03*
X422951Y715380D03*
Y740576D03*
X457151Y690780D03*
Y715976D03*
X484751Y664214D03*
Y689410D03*
X504611Y664294D03*
Y689490D03*
X692271Y1340890D03*
Y1366086D03*
X720271Y1342520D03*
Y1367716D03*
X752741Y1342430D03*
Y1367626D03*
X1083532Y1325434D03*
Y1350630D03*
X1119632Y1325634D03*
Y1350830D03*
X1180732Y1325534D03*
Y1350730D03*
X1253690Y1279688D03*
Y1304884D03*
X1283112Y1279688D03*
Y1304884D03*
X1317705Y1279603D03*
Y1304799D03*
X1352105Y1279578D03*
Y1304774D03*
X1386790Y1298902D03*
Y1324098D03*
X1401289Y681278D03*
Y706474D03*
X1437261Y713737D03*
Y738933D03*
X1467789Y733482D03*
Y758678D03*
X1496651Y733314D03*
Y758510D03*
X1531030Y733327D03*
Y758523D03*
X1566441Y711374D03*
Y736570D03*
X1601051Y677752D03*
Y702948D03*
X1636101Y658622D03*
Y683818D03*
X1667987Y1341580D03*
Y1366776D03*
X1700467Y1341760D03*
Y1366956D03*
X1727967Y1340380D03*
Y1365576D03*
X1748688Y1483573D03*
Y1508769D03*
X1771388Y1483573D03*
Y1508769D03*
X1758188Y1524433D03*
Y1549629D03*
X1795388Y1483573D03*
Y1508769D03*
X1787093Y1524479D03*
Y1549675D03*
X1819388Y1483573D03*
Y1508769D03*
G54D31*
X60303Y20354D03*
X312921Y24291D03*
X326731Y663237D03*
X363731D03*
X443467Y594259D03*
X505185Y41141D03*
X754645Y1436735D03*
X757803Y45078D03*
X929331Y160413D03*
X922441Y237697D03*
X1077638Y133866D03*
X1166535Y1422322D03*
X1291146Y1385558D03*
X1320516D03*
X1425533Y601230D03*
X1487677Y649988D03*
X1524437Y650208D03*
X1534712Y20354D03*
X1701285Y208455D03*
X1700840Y1434362D03*
X1731660Y208455D03*
X1770442Y294777D03*
X1787330Y24291D03*
X1800002Y294777D03*
G54D115*
X1240449Y733779D03*
X1271146Y749877D03*
G54D14*
X27048Y1533228D03*
X79590Y1369350D03*
X137284Y1533228D03*
X215418Y658055D03*
X276440Y1357539D03*
X420125Y656008D03*
X443764Y1339823D03*
X523173Y578174D03*
X681440Y1385138D03*
X791678D03*
X873622Y1145275D03*
X983858D03*
X1052960Y1369350D03*
X1249812Y1357539D03*
X1370284Y582303D03*
X1417134Y1339823D03*
X1533552Y682342D03*
X1629732Y1383523D03*
X1664890Y642972D03*
X1714330Y1570984D03*
X1739968Y1383527D03*
X1761575Y159134D03*
X1824566Y1570988D03*
X1838150Y201929D03*
G54D23*
X30000Y1505100D03*
Y1510900D03*
X499586Y161518D03*
Y167318D03*
X543749Y123617D03*
Y129417D03*
X537242Y164428D03*
Y158628D03*
X553380Y138093D03*
Y143893D03*
X1823514Y1529093D03*
Y1534893D03*
G54D107*
X906795Y869555D03*
X909355D03*
X906795Y886681D03*
X909355D03*
X941203Y869792D03*
X938643D03*
X941203Y886918D03*
X938643D03*
X960280Y869937D03*
X957720D03*
X960280Y887063D03*
X957720D03*
G54D41*
X230905Y1644448D03*
Y1658621D03*
Y1672795D03*
Y1686968D03*
Y1701141D03*
Y1715314D03*
Y1729488D03*
X246653Y1644448D03*
X238779Y1648385D03*
X246653Y1658621D03*
X238779Y1662558D03*
X246653Y1672795D03*
X238779Y1676732D03*
X246653Y1686968D03*
X238779Y1690905D03*
X246653Y1701141D03*
X238779Y1705078D03*
X246653Y1715314D03*
X238779Y1719251D03*
X246653Y1729488D03*
X238779Y1733425D03*
X254527Y1648385D03*
Y1662558D03*
Y1676732D03*
Y1690905D03*
Y1705078D03*
Y1719251D03*
Y1733425D03*
X262401Y1644448D03*
X270275Y1648385D03*
X262401Y1658621D03*
X270275Y1662558D03*
X262401Y1672795D03*
X270275Y1676732D03*
X262401Y1686968D03*
X270275Y1690905D03*
X262401Y1701141D03*
X270275Y1705078D03*
X262401Y1715314D03*
X270275Y1719251D03*
X262401Y1729488D03*
X270275Y1733425D03*
X278149Y1644448D03*
X286023Y1648385D03*
X278149Y1658621D03*
X286023Y1662558D03*
X278149Y1672795D03*
X286023Y1676732D03*
X278149Y1686968D03*
X286023Y1690905D03*
X278149Y1701141D03*
X286023Y1705078D03*
X278149Y1715314D03*
X286023Y1719251D03*
X278149Y1729488D03*
X286023Y1733425D03*
X297835Y1672795D03*
X305709Y1676732D03*
X297835Y1686968D03*
X305709Y1690905D03*
X297835Y1701141D03*
X305709Y1705078D03*
X297835Y1715314D03*
X305709Y1719251D03*
X297835Y1729488D03*
X305709Y1733425D03*
X313583Y1672795D03*
X321457Y1676732D03*
X313583Y1686968D03*
X321457Y1690905D03*
X313583Y1701141D03*
X321457Y1705078D03*
X313583Y1715314D03*
X321457Y1719251D03*
X313583Y1729488D03*
X321457Y1733425D03*
X329331Y1672795D03*
Y1686968D03*
Y1701141D03*
Y1715314D03*
Y1729488D03*
X345079Y1672795D03*
X337205Y1676732D03*
X345079Y1686968D03*
X337205Y1690905D03*
X345079Y1701141D03*
X337205Y1705078D03*
X345079Y1715314D03*
X337205Y1719251D03*
X345079Y1729488D03*
X337205Y1733425D03*
X352953Y1676732D03*
Y1690905D03*
Y1705078D03*
Y1719251D03*
Y1733425D03*
X495078Y1672795D03*
Y1686968D03*
Y1701141D03*
Y1715314D03*
Y1729488D03*
X510826Y1672795D03*
X502952Y1676732D03*
X510826Y1686968D03*
X502952Y1690905D03*
X510826Y1701141D03*
X502952Y1705078D03*
X510826Y1715314D03*
X502952Y1719251D03*
X510826Y1729488D03*
X502952Y1733425D03*
X526574Y1672795D03*
X518700Y1676732D03*
X526574Y1686968D03*
X518700Y1690905D03*
X526574Y1701141D03*
X518700Y1705078D03*
X526574Y1715314D03*
X518700Y1719251D03*
X526574Y1729488D03*
X518700Y1733425D03*
X542322Y1672795D03*
X534448Y1676732D03*
X542322Y1686968D03*
X534448Y1690905D03*
X542322Y1701141D03*
X534448Y1705078D03*
X542322Y1715314D03*
X534448Y1719251D03*
X542322Y1729488D03*
X534448Y1733425D03*
X550196Y1676732D03*
Y1690905D03*
Y1705078D03*
Y1719251D03*
Y1733425D03*
X562008Y1672795D03*
X569882Y1676732D03*
X562008Y1686968D03*
X569882Y1690905D03*
X562008Y1701141D03*
X569882Y1705078D03*
X562008Y1715314D03*
X569882Y1719251D03*
X562008Y1729488D03*
X569882Y1733425D03*
X577756Y1672795D03*
X585630Y1676732D03*
X577756Y1686968D03*
X585630Y1690905D03*
X577756Y1701141D03*
X585630Y1705078D03*
X577756Y1715314D03*
X585630Y1719251D03*
X577756Y1729488D03*
X585630Y1733425D03*
X593504Y1672795D03*
X601378Y1676732D03*
X593504Y1686968D03*
X601378Y1690905D03*
X593504Y1701141D03*
X601378Y1705078D03*
X593504Y1715314D03*
X601378Y1719251D03*
X593504Y1729488D03*
X601378Y1733425D03*
X609252Y1672795D03*
X617126Y1676732D03*
X609252Y1686968D03*
X617126Y1690905D03*
X609252Y1701141D03*
X617126Y1705078D03*
X609252Y1715314D03*
X617126Y1719251D03*
X609252Y1729488D03*
X617126Y1733425D03*
X1238778Y1672795D03*
Y1686968D03*
Y1701141D03*
Y1715314D03*
Y1729488D03*
X1254526Y1672795D03*
X1246652Y1676732D03*
X1254526Y1686968D03*
X1246652Y1690905D03*
X1254526Y1701141D03*
X1246652Y1705078D03*
X1254526Y1715314D03*
X1246652Y1719251D03*
X1254526Y1729488D03*
X1246652Y1733425D03*
X1270274Y1672795D03*
X1262400Y1676732D03*
X1270274Y1686968D03*
X1262400Y1690905D03*
X1270274Y1701141D03*
X1262400Y1705078D03*
X1270274Y1715314D03*
X1262400Y1719251D03*
X1270274Y1729488D03*
X1262400Y1733425D03*
X1286022Y1672795D03*
X1278148Y1676732D03*
X1286022Y1686968D03*
X1278148Y1690905D03*
X1286022Y1701141D03*
X1278148Y1705078D03*
X1286022Y1715314D03*
X1278148Y1719251D03*
X1286022Y1729488D03*
X1278148Y1733425D03*
X1305708Y1672795D03*
Y1686968D03*
X1293896Y1676732D03*
X1305708Y1701141D03*
X1293896Y1690905D03*
X1305708Y1715314D03*
X1293896Y1705078D03*
X1305708Y1729488D03*
X1293896Y1719251D03*
Y1733425D03*
X1313582Y1676732D03*
Y1690905D03*
Y1705078D03*
Y1719251D03*
Y1733425D03*
X1321456Y1672795D03*
X1329330Y1676732D03*
X1321456Y1686968D03*
X1329330Y1690905D03*
X1321456Y1701141D03*
X1329330Y1705078D03*
X1321456Y1715314D03*
X1329330Y1719251D03*
X1321456Y1729488D03*
X1329330Y1733425D03*
X1337204Y1672795D03*
X1345078Y1676732D03*
X1337204Y1686968D03*
X1345078Y1690905D03*
X1337204Y1701141D03*
X1345078Y1705078D03*
X1337204Y1715314D03*
X1345078Y1719251D03*
X1337204Y1729488D03*
X1345078Y1733425D03*
X1352952Y1672795D03*
X1360826Y1676732D03*
X1352952Y1686968D03*
X1360826Y1690905D03*
X1352952Y1701141D03*
X1360826Y1705078D03*
X1352952Y1715314D03*
X1360826Y1719251D03*
X1352952Y1729488D03*
X1360826Y1733425D03*
X1502952Y1672795D03*
X1510826Y1676732D03*
X1502952Y1686968D03*
X1510826Y1690905D03*
X1502952Y1701141D03*
X1510826Y1705078D03*
X1502952Y1715314D03*
X1510826Y1719251D03*
X1502952Y1729488D03*
X1510826Y1733425D03*
X1518700Y1672795D03*
X1526574Y1676732D03*
X1518700Y1686968D03*
X1526574Y1690905D03*
X1518700Y1701141D03*
X1526574Y1705078D03*
X1518700Y1715314D03*
X1526574Y1719251D03*
X1518700Y1729488D03*
X1526574Y1733425D03*
X1534448Y1672795D03*
X1542322Y1676732D03*
X1534448Y1686968D03*
X1542322Y1690905D03*
X1534448Y1701141D03*
X1542322Y1705078D03*
X1534448Y1715314D03*
X1542322Y1719251D03*
X1534448Y1729488D03*
X1542322Y1733425D03*
X1550196Y1672795D03*
X1558070Y1676732D03*
X1550196Y1686968D03*
X1558070Y1690905D03*
X1550196Y1701141D03*
X1558070Y1705078D03*
X1550196Y1715314D03*
X1558070Y1719251D03*
X1550196Y1729488D03*
X1558070Y1733425D03*
X1569882Y1672795D03*
Y1686968D03*
Y1701141D03*
Y1715314D03*
Y1729488D03*
X1585630Y1672795D03*
X1577756Y1676732D03*
X1585630Y1686968D03*
X1577756Y1690905D03*
X1585630Y1701141D03*
X1577756Y1705078D03*
X1585630Y1715314D03*
X1577756Y1719251D03*
X1585630Y1729488D03*
X1577756Y1733425D03*
X1601378Y1672795D03*
X1593504Y1676732D03*
X1601378Y1686968D03*
X1593504Y1690905D03*
X1601378Y1701141D03*
X1593504Y1705078D03*
X1601378Y1715314D03*
X1593504Y1719251D03*
X1601378Y1729488D03*
X1593504Y1733425D03*
X1617126Y1672795D03*
X1609252Y1676732D03*
X1617126Y1686968D03*
X1609252Y1690905D03*
X1617126Y1701141D03*
X1609252Y1705078D03*
X1617126Y1715314D03*
X1609252Y1719251D03*
X1617126Y1729488D03*
X1609252Y1733425D03*
X1625000Y1676732D03*
Y1690905D03*
Y1705078D03*
Y1719251D03*
Y1733425D03*
G54D125*
X1900275Y-39973D03*
Y572227D03*
X1898799Y1198198D03*
Y1810398D03*
X1910275Y-39973D03*
Y572227D03*
X1908799Y1198198D03*
Y1810398D03*
X1921395Y-39963D03*
X1931395D03*
Y572237D03*
X1921395D03*
X1931395D03*
X1921395D03*
Y1184437D03*
X1931395D03*
X1929766Y1198160D03*
X1919766D03*
Y1810360D03*
X1929766D03*
X1942395Y-39783D03*
Y572417D03*
D03*
X1940886Y1198170D03*
X1942395Y1184617D03*
X1940886Y1810370D03*
X1952395Y-39783D03*
X1963362Y-39821D03*
Y572379D03*
X1952395Y572417D03*
D03*
X1963362Y572379D03*
X1950886Y1198170D03*
X1952395Y1184617D03*
X1963362Y1184579D03*
X1961856Y1198170D03*
X1950886Y1810370D03*
X1961856D03*
X1973362Y-39821D03*
Y572379D03*
D03*
Y1184579D03*
X1971856Y1198170D03*
Y1810370D03*
X1984482Y-39811D03*
Y572389D03*
D03*
Y1184589D03*
X1982856Y1198350D03*
X1992856D03*
Y1810550D03*
X1982856D03*
X1994482Y-39811D03*
X2005452D03*
Y572389D03*
X1994482D03*
D03*
X2005452D03*
X1994482Y1184589D03*
X2005452D03*
X2003823Y1198312D03*
Y1810512D03*
X2015452Y-39811D03*
Y572389D03*
D03*
Y1184589D03*
X2013823Y1198312D03*
Y1810512D03*
X2036452Y-39631D03*
X2026452D03*
Y572569D03*
X2036452D03*
X2026452D03*
X2036452D03*
Y1184769D03*
X2026452D03*
X2047419Y-39669D03*
Y572531D03*
D03*
Y1184731D03*
X2057419Y-39669D03*
Y572531D03*
D03*
Y1184731D03*
X2068539Y572541D03*
X2078539D03*
Y1184741D03*
X2068539D03*
G54D116*
X1249152Y60384D03*
X1431175Y87432D03*
G54D32*
X79729Y289822D03*
Y310256D03*
X89729Y289822D03*
Y310256D03*
X757184Y1702772D03*
Y1712772D03*
X1072863Y1409176D03*
Y1419176D03*
X1080970Y1640958D03*
Y1650958D03*
X1225530Y67471D03*
X1299439Y102812D03*
Y112812D03*
X1454797Y80345D03*
X1530377Y581353D03*
X1540377D03*
G54D50*
X360649Y558332D03*
X361000Y568790D03*
X1473784Y553086D03*
G54D60*
X401829Y1003273D03*
X445917Y971551D03*
X1378015Y1003283D03*
X1422059Y971550D03*
G54D15*
X44000Y154200D03*
X31818Y1424257D03*
X441043Y1672205D03*
Y1718465D03*
X1416437Y1672205D03*
Y1718465D03*
X1800449Y126194D03*
X1804650Y1667292D03*
G54D24*
X36147Y1504577D03*
Y1511577D03*
X42955Y1504577D03*
Y1511577D03*
X70864Y1504487D03*
X77749Y1504524D03*
X70864Y1511487D03*
X77749Y1511524D03*
X70475Y1527169D03*
Y1534169D03*
X78405Y1527169D03*
Y1534169D03*
X97994Y1327151D03*
Y1334151D03*
X112826Y1526634D03*
Y1533634D03*
X104887Y1526568D03*
Y1533568D03*
X112220Y1581306D03*
Y1588306D03*
X125558Y1327168D03*
Y1334168D03*
X117017Y1361811D03*
Y1368811D03*
X125395Y1361811D03*
Y1368811D03*
X117017Y1384054D03*
Y1377054D03*
X133994Y1327251D03*
Y1334251D03*
X157995Y1361811D03*
Y1368811D03*
X149617Y1361811D03*
Y1368811D03*
Y1384054D03*
Y1377054D03*
X170266Y1327168D03*
X162058D03*
X170266Y1334168D03*
X162058D03*
X186682Y1327168D03*
X178474D03*
X186682Y1334168D03*
X178474D03*
X182317Y1361811D03*
Y1368811D03*
Y1384054D03*
Y1377054D03*
X194494Y1327151D03*
Y1334151D03*
X190695Y1361811D03*
Y1368811D03*
X215217Y1361811D03*
Y1368811D03*
Y1384054D03*
Y1377054D03*
X229994Y1327551D03*
Y1334551D03*
X223595Y1361811D03*
Y1368811D03*
X246312Y668330D03*
Y661330D03*
X240711Y694848D03*
Y701848D03*
X238894Y1327551D03*
X247058Y1327568D03*
X238894Y1334551D03*
X247058Y1334568D03*
X248017Y1361811D03*
Y1368811D03*
Y1384054D03*
Y1377054D03*
X253551Y646578D03*
Y653578D03*
X254312Y668330D03*
Y661330D03*
X259157Y694728D03*
Y701728D03*
X249551Y694728D03*
Y701728D03*
X255558Y1327551D03*
Y1334551D03*
X256395Y1361811D03*
Y1368811D03*
X268281Y694728D03*
Y701728D03*
X274621Y726408D03*
Y733408D03*
X271324Y1520453D03*
Y1527453D03*
X286181Y681028D03*
Y688028D03*
X279042Y702371D03*
Y695371D03*
X287042Y702371D03*
Y695371D03*
X281617Y1315665D03*
Y1322665D03*
X289995Y1315665D03*
Y1322665D03*
X281617Y1337908D03*
Y1330908D03*
X278132Y1520453D03*
Y1527453D03*
X285286Y1530646D03*
Y1537646D03*
X302181Y730028D03*
Y737028D03*
X293221Y1280878D03*
Y1287878D03*
X318651Y701078D03*
X311912Y715621D03*
X319912D03*
X318651Y708078D03*
X311912Y722621D03*
X319912D03*
X312051Y749878D03*
Y756878D03*
X320954Y1281194D03*
Y1288194D03*
X314513Y1315637D03*
Y1322637D03*
Y1337880D03*
Y1330880D03*
X327831Y1281208D03*
Y1288208D03*
X322891Y1315637D03*
Y1322637D03*
X344221Y715429D03*
Y722429D03*
X341151Y749878D03*
Y756878D03*
X347417Y1315580D03*
Y1322580D03*
Y1337823D03*
Y1330823D03*
X352599Y700186D03*
Y707186D03*
Y715429D03*
Y722429D03*
X355314Y1281327D03*
X362201Y1281413D03*
X355314Y1288327D03*
X362201Y1288413D03*
X355795Y1315580D03*
Y1322580D03*
X377812Y715221D03*
Y722221D03*
X371551Y749878D03*
Y756878D03*
X380217Y1315780D03*
Y1322780D03*
Y1338023D03*
Y1331023D03*
X385251Y700778D03*
X385812Y715221D03*
X385251Y707778D03*
X385812Y722221D03*
X389701Y1283213D03*
Y1290213D03*
X396176Y1307751D03*
Y1300751D03*
X388595Y1315780D03*
Y1322780D03*
X410712Y697721D03*
Y704721D03*
X409151Y731978D03*
Y738978D03*
X401280Y749563D03*
Y756563D03*
X399386Y1520453D03*
X406194D03*
X399386Y1527453D03*
X406194D03*
X418051Y682878D03*
X418712Y697721D03*
X418051Y689878D03*
X418712Y704721D03*
X424373Y1307868D03*
Y1300868D03*
X421177Y1335111D03*
Y1342111D03*
X412799Y1335111D03*
Y1342111D03*
Y1357354D03*
Y1350354D03*
X421397Y1530646D03*
Y1537646D03*
X436252Y672781D03*
Y679781D03*
X437851Y747958D03*
Y754958D03*
X448090Y131742D03*
Y138742D03*
X450551Y658478D03*
X443112Y672821D03*
X451212D03*
X450551Y665478D03*
X443112Y679821D03*
X451212D03*
X443351Y705949D03*
Y712949D03*
X468912Y653421D03*
Y646421D03*
X462013Y653264D03*
Y646264D03*
X470951Y693378D03*
Y700378D03*
X483251Y631978D03*
Y638978D03*
X475812Y653421D03*
Y646421D03*
X483812Y653421D03*
Y646421D03*
X495279Y612162D03*
Y619162D03*
X516351Y597778D03*
X502112Y612221D03*
X516351Y604778D03*
X509012Y612221D03*
X502112Y619221D03*
X509012D03*
X517012Y612221D03*
Y619221D03*
X517931Y646858D03*
Y653858D03*
X524931Y646858D03*
Y653858D03*
X538851Y646678D03*
Y653678D03*
X531951Y646678D03*
Y653678D03*
X535497Y1520453D03*
X542305D03*
X535497Y1527453D03*
X542305D03*
X549459Y1530646D03*
Y1537646D03*
X678552Y1343988D03*
Y1350988D03*
X706121Y1343988D03*
Y1350988D03*
X724198Y1379230D03*
Y1386230D03*
X724900Y1401346D03*
Y1394346D03*
X735271Y1343988D03*
Y1350988D03*
X732313Y1379230D03*
Y1386230D03*
X766455Y1343360D03*
Y1350360D03*
X756980Y1379330D03*
Y1386330D03*
X765095Y1379330D03*
Y1386330D03*
X757919Y1401446D03*
Y1394446D03*
X779280Y1299759D03*
Y1306759D03*
X771908Y1379184D03*
Y1386184D03*
X795280Y1299759D03*
X787280D03*
X795280Y1306759D03*
X787280D03*
X803280Y1299759D03*
Y1306759D03*
X885823Y1240420D03*
Y1247420D03*
X900923Y1240420D03*
X892823D03*
X900923Y1247420D03*
X892823D03*
X916023Y1240420D03*
X909023D03*
X916023Y1247420D03*
X909023D03*
X944807Y1240420D03*
Y1247420D03*
X951807Y1240420D03*
X959907D03*
X951807Y1247420D03*
X959907D03*
X962000Y1299000D03*
Y1292000D03*
X968580Y208799D03*
Y215799D03*
X968007Y1240420D03*
X975007D03*
X968007Y1247420D03*
X975007D03*
X1069732Y1327132D03*
Y1334132D03*
X1097296Y1327149D03*
Y1334149D03*
X1097133Y1361792D03*
Y1368792D03*
X1088755Y1361792D03*
Y1368792D03*
Y1384035D03*
Y1377035D03*
X1105732Y1327232D03*
Y1334232D03*
X1121355Y1361792D03*
Y1368792D03*
Y1384035D03*
Y1377035D03*
X1141304Y1327149D03*
X1133596D03*
X1141304Y1334149D03*
X1133596D03*
X1129733Y1361792D03*
Y1368792D03*
X1149012Y1327149D03*
X1156720D03*
X1149012Y1334149D03*
X1156720D03*
X1154055Y1361792D03*
Y1368792D03*
Y1384035D03*
Y1377035D03*
X1144420Y1386080D03*
Y1393080D03*
X1166232Y1327132D03*
Y1334132D03*
X1162433Y1361792D03*
Y1368792D03*
X1186955Y1361792D03*
Y1368792D03*
Y1384035D03*
Y1377035D03*
X1201732Y1327532D03*
Y1334532D03*
X1195333Y1361792D03*
Y1368792D03*
X1210632Y1327532D03*
Y1334532D03*
X1227296Y1327532D03*
X1218796Y1327549D03*
X1227296Y1334532D03*
X1218796Y1334549D03*
X1228133Y1361792D03*
Y1368792D03*
X1219755Y1361792D03*
Y1368792D03*
Y1384035D03*
Y1377035D03*
X1257746Y1315646D03*
Y1322646D03*
Y1337889D03*
Y1330889D03*
X1269350Y1280859D03*
Y1287859D03*
X1266124Y1315646D03*
Y1322646D03*
X1290642Y1315618D03*
Y1322618D03*
Y1337861D03*
Y1330861D03*
X1279197Y1553453D03*
X1286005D03*
X1279197Y1560453D03*
X1286005D03*
X1303960Y1281189D03*
X1297083Y1281175D03*
X1303960Y1288189D03*
X1297083Y1288175D03*
X1299020Y1315618D03*
Y1322618D03*
X1293159Y1563646D03*
Y1570646D03*
X1321334Y591261D03*
Y598261D03*
X1313234Y591261D03*
Y598261D03*
X1329376Y591243D03*
Y598243D03*
X1331443Y1281308D03*
Y1288308D03*
X1331924Y1315561D03*
Y1322561D03*
X1323546Y1315561D03*
Y1322561D03*
Y1337804D03*
Y1330804D03*
X1338330Y1281394D03*
Y1288394D03*
X1364034Y616090D03*
Y623090D03*
X1356964Y638394D03*
Y631394D03*
X1364964Y638394D03*
Y631394D03*
X1351930Y664953D03*
Y671953D03*
X1360278Y664953D03*
Y671953D03*
X1365830Y1283194D03*
Y1290194D03*
X1364724Y1315761D03*
Y1322761D03*
X1356346Y1315761D03*
Y1322761D03*
Y1338004D03*
Y1331004D03*
X1368602Y664953D03*
Y671953D03*
X1379644Y671110D03*
Y678110D03*
X1372305Y1307732D03*
Y1300732D03*
X1389664Y671294D03*
Y664294D03*
X1387500Y696943D03*
Y703943D03*
X1388928Y1335092D03*
Y1342092D03*
Y1357335D03*
Y1350335D03*
X1396924Y648980D03*
Y655980D03*
X1397664Y671294D03*
Y664294D03*
X1400502Y1307849D03*
Y1300849D03*
X1397306Y1335092D03*
Y1342092D03*
X1407259Y1553453D03*
Y1560453D03*
X1415044Y703880D03*
X1422264Y703874D03*
Y696874D03*
X1415044Y710880D03*
X1423390Y729673D03*
Y736673D03*
X1414067Y1553453D03*
Y1560453D03*
X1429484Y681610D03*
Y688610D03*
X1430264Y703874D03*
Y696874D03*
X1429271Y1563646D03*
Y1570646D03*
X1454431Y715697D03*
Y722697D03*
X1452334Y749745D03*
Y756745D03*
X1463189Y701204D03*
X1462809Y715697D03*
X1463189Y708204D03*
X1462809Y722697D03*
X1482900Y749440D03*
Y756440D03*
X1495624Y701137D03*
X1496264Y716451D03*
X1488264D03*
X1495624Y708137D03*
X1496264Y723451D03*
X1488264D03*
X1510454Y749787D03*
Y756787D03*
X1528334Y701087D03*
X1521064Y716451D03*
X1529064D03*
X1528334Y708087D03*
X1521064Y723451D03*
X1529064D03*
X1517300Y749770D03*
Y756770D03*
X1543371Y1553453D03*
Y1560453D03*
X1554194Y701511D03*
Y694511D03*
X1552500Y727340D03*
Y734340D03*
X1546047Y767488D03*
Y774488D03*
X1550179Y1553453D03*
X1557333Y1563646D03*
X1550179Y1560453D03*
X1557333Y1570646D03*
X1570394Y670805D03*
Y663805D03*
X1561464Y679157D03*
Y686157D03*
X1562194Y701511D03*
Y694511D03*
X1580067Y667758D03*
Y660758D03*
X1586964Y667742D03*
Y660742D03*
X1587320Y700330D03*
Y707330D03*
X1580154Y727340D03*
Y734340D03*
X1604501Y642232D03*
Y635232D03*
X1594184Y645338D03*
Y652338D03*
X1594964Y667742D03*
Y660742D03*
X1612692Y643297D03*
Y636297D03*
X1614804Y694238D03*
Y701238D03*
X1623059Y592354D03*
Y599354D03*
X1630259Y592315D03*
Y599315D03*
X1627184Y626378D03*
X1627964Y641742D03*
X1627184Y633378D03*
X1619964Y641742D03*
X1627964Y648742D03*
X1619964D03*
X1622300Y675268D03*
Y682268D03*
X1646177Y1342988D03*
Y1349988D03*
X1649854Y675268D03*
Y682268D03*
X1654177Y1342988D03*
Y1349988D03*
X1671931Y1378519D03*
Y1385519D03*
X1672633Y1400635D03*
Y1393635D03*
X1683177Y1342988D03*
Y1349988D03*
X1679931Y1378519D03*
Y1385519D03*
X1704713Y1378619D03*
Y1385619D03*
X1705652Y1400735D03*
Y1393735D03*
X1714198Y1342649D03*
Y1349649D03*
X1712713Y1378619D03*
Y1385619D03*
X1719841Y1378767D03*
Y1385767D03*
X1723110Y1431730D03*
Y1424730D03*
X1744148Y1535580D03*
Y1528580D03*
X1763983Y205965D03*
X1756923Y205902D03*
X1763983Y212965D03*
X1756923Y212902D03*
X1765310Y1559705D03*
Y1566705D03*
X1756904Y1559705D03*
Y1566705D03*
X1772354Y183529D03*
Y190529D03*
X1777864Y211569D03*
Y204569D03*
X1770824Y211559D03*
Y204559D03*
X1783296Y255433D03*
Y262433D03*
X1773352Y1537361D03*
Y1530361D03*
X1791776Y255433D03*
Y262433D03*
X1792179Y1559705D03*
Y1566705D03*
X1799796Y255433D03*
Y262433D03*
X1808422Y1535516D03*
Y1528516D03*
X1800579Y1559705D03*
Y1566705D03*
X1816922Y1535516D03*
Y1528516D03*
G54D117*
X1447227Y554649D03*
X1443487Y545987D03*
X1450967D03*
G54D108*
X909010Y924013D03*
X912947D03*
X907041D03*
X910978D03*
X907041Y934839D03*
X912947D03*
X909010D03*
X910978D03*
G54D51*
X365338Y567553D03*
Y565978D03*
Y564403D03*
Y562828D03*
Y561254D03*
Y578576D03*
Y577002D03*
Y575427D03*
Y573852D03*
Y572277D03*
Y570702D03*
Y569128D03*
X387976Y561254D03*
Y562828D03*
Y564403D03*
Y565978D03*
Y567553D03*
Y569128D03*
Y570702D03*
Y572277D03*
Y573852D03*
Y575427D03*
Y577002D03*
Y578576D03*
X1478438Y551816D03*
Y567564D03*
Y565989D03*
Y564414D03*
Y562839D03*
Y561264D03*
Y559690D03*
Y558115D03*
Y556540D03*
Y554965D03*
Y553390D03*
Y569138D03*
X1501076Y551816D03*
Y553390D03*
Y554965D03*
Y556540D03*
Y558115D03*
Y559690D03*
Y561264D03*
Y562839D03*
Y564414D03*
Y565989D03*
Y567564D03*
Y569138D03*
G54D42*
X230905Y1649173D03*
Y1653897D03*
Y1663346D03*
Y1668070D03*
Y1677519D03*
Y1682244D03*
Y1691692D03*
Y1696417D03*
Y1705866D03*
Y1710590D03*
Y1720039D03*
Y1724763D03*
X238779Y1653110D03*
Y1657834D03*
X246653Y1663346D03*
Y1668070D03*
Y1677519D03*
Y1682244D03*
X238779Y1681456D03*
Y1686180D03*
X246653Y1691692D03*
Y1696417D03*
X238779Y1695629D03*
Y1700354D03*
X246653Y1705866D03*
Y1710590D03*
X238779Y1709803D03*
Y1714527D03*
X246653Y1720039D03*
Y1724763D03*
X238779Y1723976D03*
Y1728700D03*
X254527Y1667283D03*
Y1672007D03*
Y1681456D03*
Y1686180D03*
Y1695629D03*
Y1700354D03*
Y1709803D03*
Y1714527D03*
Y1723976D03*
Y1728700D03*
X270275Y1653110D03*
Y1657834D03*
Y1667283D03*
Y1672007D03*
X262401Y1677519D03*
X270275Y1681456D03*
X262401Y1682244D03*
X270275Y1686180D03*
X262401Y1691692D03*
X270275Y1695629D03*
X262401Y1696417D03*
X270275Y1700354D03*
X262401Y1705866D03*
X270275Y1709803D03*
X262401Y1710590D03*
X270275Y1714527D03*
X262401Y1720039D03*
X270275Y1723976D03*
X262401Y1724763D03*
X270275Y1728700D03*
X278149Y1649173D03*
X286023Y1653110D03*
X278149Y1653897D03*
X286023Y1657834D03*
X278149Y1663346D03*
X286023Y1667283D03*
X278149Y1668070D03*
X286023Y1672007D03*
X278149Y1677519D03*
X286023Y1681456D03*
X278149Y1682244D03*
X286023Y1686180D03*
X278149Y1691692D03*
X286023Y1695629D03*
X278149Y1696417D03*
X286023Y1700354D03*
X278149Y1705866D03*
X286023Y1709803D03*
X278149Y1710590D03*
X286023Y1714527D03*
X278149Y1720039D03*
X286023Y1723976D03*
X278149Y1724763D03*
X286023Y1728700D03*
X297835Y1677519D03*
X305709Y1681456D03*
X297835Y1682244D03*
X305709Y1686180D03*
X297835Y1691692D03*
X305709Y1695629D03*
X297835Y1696417D03*
X305709Y1700354D03*
X297835Y1705866D03*
X305709Y1709803D03*
X297835Y1710590D03*
X305709Y1714527D03*
X297835Y1720039D03*
X305709Y1723976D03*
X297835Y1724763D03*
X305709Y1728700D03*
X313583Y1677519D03*
X321457Y1681456D03*
X313583Y1682244D03*
X321457Y1686180D03*
X313583Y1691692D03*
X321457Y1695629D03*
X313583Y1696417D03*
X321457Y1700354D03*
X313583Y1705866D03*
X321457Y1709803D03*
X313583Y1710590D03*
X321457Y1714527D03*
X313583Y1720039D03*
X321457Y1723976D03*
X313583Y1724763D03*
X321457Y1728700D03*
X329331Y1677519D03*
Y1682244D03*
Y1691692D03*
Y1696417D03*
Y1705866D03*
Y1710590D03*
Y1720039D03*
Y1724763D03*
X345079Y1677519D03*
Y1682244D03*
X337205Y1681456D03*
Y1686180D03*
X345079Y1691692D03*
Y1696417D03*
X337205Y1695629D03*
Y1700354D03*
X345079Y1705866D03*
Y1710590D03*
X337205Y1709803D03*
Y1714527D03*
X345079Y1720039D03*
Y1724763D03*
X337205Y1723976D03*
Y1728700D03*
X352953Y1681456D03*
Y1686180D03*
Y1695629D03*
Y1700354D03*
Y1709803D03*
Y1714527D03*
Y1723976D03*
Y1728700D03*
X495078Y1677519D03*
Y1682244D03*
Y1691692D03*
Y1696417D03*
Y1705866D03*
Y1710590D03*
Y1720039D03*
Y1724763D03*
X510826Y1677519D03*
Y1682244D03*
X502952Y1681456D03*
Y1686180D03*
X510826Y1691692D03*
Y1696417D03*
X502952Y1695629D03*
Y1700354D03*
X510826Y1705866D03*
Y1710590D03*
X502952Y1709803D03*
Y1714527D03*
X510826Y1720039D03*
Y1724763D03*
X502952Y1723976D03*
Y1728700D03*
X518700Y1681456D03*
Y1686180D03*
X526574Y1677519D03*
Y1682244D03*
X518700Y1695629D03*
Y1700354D03*
X526574Y1691692D03*
Y1696417D03*
X518700Y1709803D03*
Y1714527D03*
X526574Y1705866D03*
Y1710590D03*
X518700Y1723976D03*
Y1728700D03*
X526574Y1720039D03*
Y1724763D03*
X542322Y1677519D03*
Y1682244D03*
X534448Y1681456D03*
Y1686180D03*
X542322Y1691692D03*
Y1696417D03*
X534448Y1695629D03*
Y1700354D03*
X542322Y1705866D03*
Y1710590D03*
X534448Y1709803D03*
Y1714527D03*
X542322Y1720039D03*
Y1724763D03*
X534448Y1723976D03*
Y1728700D03*
X550196Y1681456D03*
Y1686180D03*
Y1695629D03*
Y1700354D03*
Y1709803D03*
Y1714527D03*
Y1723976D03*
Y1728700D03*
X562008Y1677519D03*
X569882Y1681456D03*
X562008Y1682244D03*
X569882Y1686180D03*
X562008Y1691692D03*
X569882Y1695629D03*
X562008Y1696417D03*
X569882Y1700354D03*
X562008Y1705866D03*
X569882Y1709803D03*
X562008Y1710590D03*
X569882Y1714527D03*
X562008Y1720039D03*
X569882Y1723976D03*
X562008Y1724763D03*
X569882Y1728700D03*
X577756Y1677519D03*
X585630Y1681456D03*
X577756Y1682244D03*
X585630Y1686180D03*
X577756Y1691692D03*
X585630Y1695629D03*
X577756Y1696417D03*
X585630Y1700354D03*
X577756Y1705866D03*
X585630Y1709803D03*
X577756Y1710590D03*
X585630Y1714527D03*
X577756Y1720039D03*
X585630Y1723976D03*
X577756Y1724763D03*
X585630Y1728700D03*
X593504Y1677519D03*
X601378Y1681456D03*
X593504Y1682244D03*
X601378Y1686180D03*
X593504Y1691692D03*
X601378Y1695629D03*
X593504Y1696417D03*
X601378Y1700354D03*
X593504Y1705866D03*
X601378Y1709803D03*
X593504Y1710590D03*
X601378Y1714527D03*
X593504Y1720039D03*
X601378Y1723976D03*
X593504Y1724763D03*
X601378Y1728700D03*
X609252Y1677519D03*
X617126Y1681456D03*
X609252Y1682244D03*
X617126Y1686180D03*
X609252Y1691692D03*
X617126Y1695629D03*
X609252Y1696417D03*
X617126Y1700354D03*
X609252Y1705866D03*
X617126Y1709803D03*
X609252Y1710590D03*
X617126Y1714527D03*
X609252Y1720039D03*
X617126Y1723976D03*
X609252Y1724763D03*
X617126Y1728700D03*
X1238778Y1677519D03*
Y1682244D03*
Y1691692D03*
Y1696417D03*
Y1705866D03*
Y1710590D03*
Y1720039D03*
Y1724763D03*
X1254526Y1677519D03*
Y1682244D03*
X1246652Y1681456D03*
Y1686180D03*
X1254526Y1691692D03*
Y1696417D03*
X1246652Y1695629D03*
Y1700354D03*
X1254526Y1705866D03*
Y1710590D03*
X1246652Y1709803D03*
Y1714527D03*
X1254526Y1720039D03*
Y1724763D03*
X1246652Y1723976D03*
Y1728700D03*
X1262400Y1681456D03*
Y1686180D03*
X1270274Y1677519D03*
Y1682244D03*
X1262400Y1695629D03*
Y1700354D03*
X1270274Y1691692D03*
Y1696417D03*
X1262400Y1709803D03*
Y1714527D03*
X1270274Y1705866D03*
Y1710590D03*
X1262400Y1723976D03*
Y1728700D03*
X1270274Y1720039D03*
Y1724763D03*
X1286022Y1677519D03*
Y1682244D03*
X1278148Y1681456D03*
Y1686180D03*
X1286022Y1691692D03*
Y1696417D03*
X1278148Y1695629D03*
Y1700354D03*
X1286022Y1705866D03*
Y1710590D03*
X1278148Y1709803D03*
Y1714527D03*
X1286022Y1720039D03*
Y1724763D03*
X1278148Y1723976D03*
Y1728700D03*
X1293896Y1681456D03*
Y1686180D03*
Y1695629D03*
Y1700354D03*
Y1709803D03*
Y1714527D03*
Y1723976D03*
Y1728700D03*
X1305708Y1677519D03*
X1313582Y1681456D03*
X1305708Y1682244D03*
X1313582Y1686180D03*
X1305708Y1691692D03*
X1313582Y1695629D03*
X1305708Y1696417D03*
X1313582Y1700354D03*
X1305708Y1705866D03*
X1313582Y1709803D03*
X1305708Y1710590D03*
X1313582Y1714527D03*
X1305708Y1720039D03*
X1313582Y1723976D03*
X1305708Y1724763D03*
X1313582Y1728700D03*
X1321456Y1677519D03*
X1329330Y1681456D03*
X1321456Y1682244D03*
X1329330Y1686180D03*
X1321456Y1691692D03*
X1329330Y1695629D03*
X1321456Y1696417D03*
X1329330Y1700354D03*
X1321456Y1705866D03*
X1329330Y1709803D03*
X1321456Y1710590D03*
X1329330Y1714527D03*
X1321456Y1720039D03*
X1329330Y1723976D03*
X1321456Y1724763D03*
X1329330Y1728700D03*
X1337204Y1677519D03*
X1345078Y1681456D03*
X1337204Y1682244D03*
X1345078Y1686180D03*
X1337204Y1691692D03*
X1345078Y1695629D03*
X1337204Y1696417D03*
X1345078Y1700354D03*
X1337204Y1705866D03*
X1345078Y1709803D03*
X1337204Y1710590D03*
X1345078Y1714527D03*
X1337204Y1720039D03*
X1345078Y1723976D03*
X1337204Y1724763D03*
X1345078Y1728700D03*
X1352952Y1677519D03*
X1360826Y1681456D03*
X1352952Y1682244D03*
X1360826Y1686180D03*
X1352952Y1691692D03*
X1360826Y1695629D03*
X1352952Y1696417D03*
X1360826Y1700354D03*
X1352952Y1705866D03*
X1360826Y1709803D03*
X1352952Y1710590D03*
X1360826Y1714527D03*
X1352952Y1720039D03*
X1360826Y1723976D03*
X1352952Y1724763D03*
X1360826Y1728700D03*
X1502952Y1677519D03*
X1510826Y1681456D03*
X1502952Y1682244D03*
X1510826Y1686180D03*
X1502952Y1691692D03*
X1510826Y1695629D03*
X1502952Y1696417D03*
X1510826Y1700354D03*
X1502952Y1705866D03*
X1510826Y1709803D03*
X1502952Y1710590D03*
X1510826Y1714527D03*
X1502952Y1720039D03*
X1510826Y1723976D03*
X1502952Y1724763D03*
X1510826Y1728700D03*
X1518700Y1677519D03*
X1526574Y1681456D03*
X1518700Y1682244D03*
X1526574Y1686180D03*
X1518700Y1691692D03*
X1526574Y1695629D03*
X1518700Y1696417D03*
X1526574Y1700354D03*
X1518700Y1705866D03*
X1526574Y1709803D03*
X1518700Y1710590D03*
X1526574Y1714527D03*
X1518700Y1720039D03*
X1526574Y1723976D03*
X1518700Y1724763D03*
X1526574Y1728700D03*
X1534448Y1677519D03*
X1542322Y1681456D03*
X1534448Y1682244D03*
X1542322Y1686180D03*
X1534448Y1691692D03*
X1542322Y1695629D03*
X1534448Y1696417D03*
X1542322Y1700354D03*
X1534448Y1705866D03*
X1542322Y1709803D03*
X1534448Y1710590D03*
X1542322Y1714527D03*
X1534448Y1720039D03*
X1542322Y1723976D03*
X1534448Y1724763D03*
X1542322Y1728700D03*
X1550196Y1677519D03*
X1558070Y1681456D03*
X1550196Y1682244D03*
X1558070Y1686180D03*
X1550196Y1691692D03*
X1558070Y1695629D03*
X1550196Y1696417D03*
X1558070Y1700354D03*
X1550196Y1705866D03*
X1558070Y1709803D03*
X1550196Y1710590D03*
X1558070Y1714527D03*
X1550196Y1720039D03*
X1558070Y1723976D03*
X1550196Y1724763D03*
X1558070Y1728700D03*
X1569882Y1677519D03*
Y1682244D03*
Y1691692D03*
Y1696417D03*
Y1705866D03*
Y1710590D03*
Y1720039D03*
Y1724763D03*
X1585630Y1677519D03*
Y1682244D03*
X1577756Y1681456D03*
Y1686180D03*
X1585630Y1691692D03*
Y1696417D03*
X1577756Y1695629D03*
Y1700354D03*
X1585630Y1705866D03*
Y1710590D03*
X1577756Y1709803D03*
Y1714527D03*
X1585630Y1720039D03*
Y1724763D03*
X1577756Y1723976D03*
Y1728700D03*
X1593504Y1681456D03*
Y1686180D03*
X1601378Y1677519D03*
Y1682244D03*
X1593504Y1695629D03*
Y1700354D03*
X1601378Y1691692D03*
Y1696417D03*
X1593504Y1709803D03*
Y1714527D03*
X1601378Y1705866D03*
Y1710590D03*
X1593504Y1723976D03*
Y1728700D03*
X1601378Y1720039D03*
Y1724763D03*
X1617126Y1677519D03*
Y1682244D03*
X1609252Y1681456D03*
Y1686180D03*
X1617126Y1691692D03*
Y1696417D03*
X1609252Y1695629D03*
Y1700354D03*
X1617126Y1705866D03*
Y1710590D03*
X1609252Y1709803D03*
Y1714527D03*
X1617126Y1720039D03*
Y1724763D03*
X1609252Y1723976D03*
Y1728700D03*
X1625000Y1681456D03*
Y1686180D03*
Y1695629D03*
Y1700354D03*
Y1709803D03*
Y1714527D03*
Y1723976D03*
Y1728700D03*
G54D126*
X1900275Y-29973D03*
Y562227D03*
X1898799Y1208198D03*
Y1800398D03*
X1910275Y-29973D03*
Y562227D03*
X1908799Y1208198D03*
Y1800398D03*
X1921395Y-29963D03*
X1931395D03*
Y562237D03*
X1921395D03*
X1931395Y582237D03*
X1921395D03*
Y1174437D03*
X1931395D03*
X1929766Y1208160D03*
X1919766D03*
Y1800360D03*
X1929766D03*
X1942395Y-29783D03*
Y562417D03*
Y582417D03*
Y1174617D03*
X1940886Y1208170D03*
Y1800370D03*
X1952395Y-29783D03*
Y562417D03*
Y582417D03*
Y1174617D03*
X1950886Y1208170D03*
X1961856D03*
X1950886Y1800370D03*
X1961856D03*
X1963362Y-29821D03*
X1973362D03*
Y562379D03*
X1963362D03*
X1973362Y582379D03*
X1963362D03*
Y1174579D03*
X1973362D03*
X1971856Y1208170D03*
Y1800370D03*
X1984482Y-29811D03*
Y562389D03*
Y582389D03*
Y1174589D03*
X1982856Y1208350D03*
Y1800550D03*
X1994482Y-29811D03*
X2005452D03*
X1994482Y562389D03*
X2005452D03*
Y582389D03*
X1994482D03*
Y1174589D03*
X2005452D03*
X1992856Y1208350D03*
X2003823Y1208312D03*
X1992856Y1800550D03*
X2003823Y1800512D03*
X2015452Y-29811D03*
Y562389D03*
Y582389D03*
Y1174589D03*
X2013823Y1208312D03*
Y1800512D03*
X2036452Y-29631D03*
X2026452D03*
Y562569D03*
X2036452D03*
X2026452Y582569D03*
X2036452D03*
Y1174769D03*
X2026452D03*
X2047419Y-29669D03*
Y562531D03*
Y582531D03*
Y1174731D03*
X2057419Y-29669D03*
Y562531D03*
Y582531D03*
Y1174731D03*
X2068539Y582541D03*
X2078539D03*
Y1174741D03*
X2068539D03*
G54D33*
X80948Y525513D03*
Y521613D03*
X94474Y766871D03*
X108817Y1380530D03*
X124174Y766871D03*
X153875D03*
X183576D03*
X208818D03*
X262239Y649587D03*
X273208Y588237D03*
X430793Y686423D03*
X463193Y661823D03*
X474808Y291492D03*
X482893Y291293D03*
X495839Y635323D03*
X516020Y105370D03*
Y109270D03*
X535170Y111230D03*
Y115130D03*
X547821Y79372D03*
X551721D03*
X561808Y300492D03*
X569893Y300293D03*
X571063Y314669D03*
X634794Y590504D03*
X648314Y571169D03*
X644414D03*
X638694Y590504D03*
X650258Y590316D03*
X646358D03*
X642804Y766871D03*
X638053Y1384491D03*
X653101Y1369862D03*
X652651Y1375308D03*
X672505Y766871D03*
X690105Y401775D03*
X690452Y486984D03*
X704500Y529862D03*
X702206Y766871D03*
X716373Y1398539D03*
X739553Y388270D03*
X727448Y766871D03*
X745201Y1400702D03*
X770530Y423460D03*
X768301Y438223D03*
X770918Y442510D03*
X770042Y446829D03*
X761608Y766871D03*
X757826Y1514412D03*
X772610Y434690D03*
X772677Y451374D03*
X772427Y487344D03*
X786877Y427344D03*
X786999Y435476D03*
X791308Y766871D03*
X816550D03*
X833800Y444700D03*
X869275Y750472D03*
X873175D03*
X1025493Y761819D03*
Y765719D03*
X1040915Y766870D03*
X1070616D03*
X1080555Y1380511D03*
X1100316Y766870D03*
X1109201Y1382574D03*
X1112529Y1547661D03*
X1130017Y766870D03*
X1155282Y766806D03*
X1159718Y766870D03*
X1184960D03*
X1206580Y94846D03*
X1309870Y552788D03*
X1309776Y559831D03*
X1473408Y547948D03*
X1570021Y682038D03*
X1616084Y549105D03*
X1617200Y766870D03*
X1644188D03*
X1664106Y1397828D03*
X1673889Y766870D03*
X1692934Y1399991D03*
X1701661Y644554D03*
X1705561D03*
X1708049Y766870D03*
X1737850Y766794D03*
X1767450Y766870D03*
X1792692D03*
G54D127*
G01X0Y54252D02*
G03X7874Y46378I7874J0D01*
G01X0Y305794D02*
Y54252D01*
G01X2306Y311361D02*
G03X0Y305794I5567J-5567D01*
G01X7874Y320191D02*
G02X5568Y314623I-7874J0D01*
G01D02*
X2306Y311361D01*
G01X7874Y46378D02*
X43709D01*
G01X7874Y1588077D02*
Y320191D01*
G01X23284Y1606749D02*
X10180Y1593645D01*
G01D02*
G03X7874Y1588077I5568J-5568D01*
G01X25591Y1612317D02*
G02X23284Y1606749I-7875J1D01*
G01X25591Y1732244D02*
Y1612317D01*
G01X765768Y1740118D02*
X33465D01*
G01D02*
G03X25591Y1732244I0J-7874D01*
G01X51583Y38504D02*
Y1969D01*
G01D02*
G03X53551Y0I1968J0D01*
G01X43709Y46378D02*
G02X51583Y38504I0J-7874D01*
G01X53551Y0D02*
X319693D01*
G01X137618Y605378D02*
G02X98248I-19685J0D01*
G01D02*
G02X137618I19685J0D01*
G01X197098Y260083D02*
G02X157728I-19685J0D01*
G01D02*
Y294335D01*
G01D02*
G02X197098I19685J0D01*
G01D02*
Y260083D01*
G01X319693Y0D02*
G03X321661Y1969I0J1969D01*
G01D02*
Y38504D01*
G01D02*
G02X329535Y46378I7874J0D01*
G01D02*
X488591D01*
G01X496465Y38504D02*
Y22756D01*
G01D02*
G03X498433Y20787I1968J-1D01*
G01D02*
X764575D01*
G01X488591Y46378D02*
G02X496465Y38504I0J-7874D01*
G01X723870Y260110D02*
G02X684500I-19685J0D01*
G01D02*
Y294362D01*
G01D02*
G02X723870I19685J0D01*
G01D02*
Y260110D01*
G01X783287Y605413D02*
G02X743917I-19685J0D01*
G01D02*
G02X783287I19685J0D01*
G01X764575Y20787D02*
G03X766543Y22756I-1J1969D01*
G01D02*
Y38504D01*
G01D02*
G02X774417Y46378I7874J0D01*
G01X769705Y1734921D02*
G02X767736Y1736890I0J1969D01*
G01D02*
Y1738150D01*
G01D02*
G03X765768Y1740118I-1968J0D01*
G01X774417Y46378D02*
X871260D01*
G01X1087854Y1734921D02*
X769705D01*
G01X871260Y46378D02*
G03X879134Y54252I0J7874D01*
G01D02*
Y134331D01*
G01D02*
G02X887008Y142205I7874J0D01*
G01D02*
X1011024D01*
G01X1018898Y134331D02*
Y54252D01*
G01D02*
G03X1026772Y46378I7874J0D01*
G01X1011024Y142205D02*
G02X1018898Y134331I0J-7874D01*
G01X1026772Y46378D02*
X1518118D01*
G01X1113760Y605378D02*
G02X1074390I-19685J0D01*
G01D02*
G02X1113760I19685J0D01*
G01X1824016Y1740118D02*
X1091791D01*
G01D02*
G03X1089823Y1738150I0J-1968D01*
G01D02*
Y1736890D01*
G01D02*
G02X1087854Y1734921I-1969J0D01*
G01X1173240Y260083D02*
G02X1133870I-19685J0D01*
G01D02*
Y294335D01*
G01D02*
G02X1173240I19685J0D01*
G01D02*
Y260083D01*
G01X1525992Y38504D02*
Y1969D01*
G01D02*
G03X1527961Y0I1969J0D01*
G01D02*
X1794102D01*
G01X1518118Y46378D02*
G02X1525992Y38504I0J-7874D01*
G01X1700012Y260110D02*
G02X1660642I-19685J0D01*
G01D02*
Y294362D01*
G01D02*
G02X1700012I19685J0D01*
G01D02*
Y260110D01*
G01X1759429Y605413D02*
G02X1720059I-19685J0D01*
G01D02*
G02X1759429I19685J0D01*
G01X1794102Y0D02*
G03X1796071Y1969I0J1969D01*
G01D02*
Y38504D01*
G01D02*
G02X1803945Y46378I7874J0D01*
G01D02*
X1849606D01*
G01X1831890Y1732244D02*
G03X1824016Y1740118I-7874J0D01*
G01X1843701Y1593983D02*
G03X1841395Y1599550I-7873J0D01*
G01D02*
X1834196Y1606749D01*
G01D02*
G02X1831890Y1612317I5568J5568D01*
G01D02*
Y1732244D01*
G01X1849606Y46378D02*
G03X1857480Y54252I0J7874D01*
G01Y305794D02*
G03X1855174Y311361I-7873J0D01*
G01D02*
X1846007Y320528D01*
G01D02*
G02X1843701Y326096I5568J5568D01*
G01D02*
Y1593983D01*
G01X1857480Y54252D02*
Y305794D01*
G54D16*
X36500Y320984D03*
X40000D03*
X46102Y523359D03*
X51253Y1535053D03*
X55503Y758816D03*
X65159Y776888D03*
X66871Y1604274D03*
X53633Y1637880D03*
X58633D03*
X64438Y1661303D03*
X74169Y384676D03*
X92826Y1332539D03*
X86996Y1535053D03*
X103503Y1370698D03*
X98186Y1377021D03*
X103177Y1508862D03*
X124500Y1424984D03*
X136103Y1370698D03*
X130786Y1377021D03*
X130000Y1424984D03*
X168803Y1370698D03*
X163486Y1377021D03*
X183021Y1542196D03*
X182813Y1671980D03*
X182517Y1702215D03*
X201703Y1370698D03*
X196386Y1377021D03*
X207660Y1671662D03*
X203660Y1678662D03*
X207807Y1686779D03*
Y1701897D03*
X203807Y1693779D03*
X207807Y1708897D03*
X229186Y1377021D03*
X238063Y34237D03*
X233203Y752064D03*
X234503Y1370698D03*
X268971Y802672D03*
X268103Y1324552D03*
X262786Y1330875D03*
X282716Y45849D03*
X287671Y1524106D03*
X283671D03*
X297520Y18221D03*
X297315Y585938D03*
X300999Y1324524D03*
X295682Y1330847D03*
X311716Y45849D03*
X307716D03*
X311083Y1542196D03*
X333903Y1324467D03*
X328586Y1330790D03*
X362157Y546399D03*
Y553399D03*
X361386Y1330990D03*
X366703Y1324667D03*
X385443Y594787D03*
X389443D03*
X381443D03*
X393371Y969472D03*
X393968Y1350321D03*
X397657Y580399D03*
X399285Y1343998D03*
X408000Y1638984D03*
X422048Y117844D03*
X423921Y1009407D03*
X415733Y1524106D03*
X411733D03*
X433226Y114489D03*
X425548Y117844D03*
X429726Y114489D03*
X437710Y245649D03*
X438882Y1009407D03*
X435141D03*
X427661D03*
X431401D03*
X430691Y1306228D03*
X432000Y1646484D03*
X448890Y113491D03*
X452890D03*
X451710Y244649D03*
X441710Y245649D03*
X447710Y244649D03*
X446362Y1009407D03*
X450102D03*
X442622D03*
X453842D03*
X441159Y1054750D03*
X447194Y1542196D03*
X457582Y1009407D03*
X461186Y1638934D03*
X461000Y1646984D03*
X499576Y130882D03*
X487271Y969472D03*
X503576Y130882D03*
X514576Y131482D03*
X508670Y147529D03*
X504670D03*
X504618Y166632D03*
X508618D03*
X519091Y125191D03*
Y132191D03*
X523091D03*
X539120Y37046D03*
X535117Y37019D03*
X542723Y37060D03*
X534876Y126973D03*
X538876D03*
X544680Y140477D03*
X543026Y253597D03*
X553620Y37246D03*
X549919Y37146D03*
X548610Y54719D03*
X548680Y140477D03*
X547844Y1524106D03*
X551844D03*
X589444Y71145D03*
X579771Y803372D03*
X583671Y803472D03*
X575256Y1542196D03*
X594444Y71145D03*
X602334Y67827D03*
X595571Y796672D03*
X599471D03*
X601771Y1272757D03*
X616815Y67827D03*
X610315D03*
X606263D03*
X607671Y785872D03*
X611671D03*
X605771Y1272757D03*
X622007Y72232D03*
X632800Y754084D03*
X628800D03*
X643146Y36970D03*
X647258Y1696754D03*
Y1703754D03*
X643258Y1710754D03*
X647258Y1717754D03*
X656286Y36970D03*
X662863Y58434D03*
X658735Y58423D03*
X651258Y1700604D03*
Y1714604D03*
X674963Y33226D03*
X670964D03*
X678291Y55166D03*
X670500Y387846D03*
X675500Y396346D03*
X680621Y33226D03*
X692466Y41434D03*
X685838Y33204D03*
X682291Y54306D03*
X686291Y55666D03*
X681500Y119984D03*
X683500Y396346D03*
X679500D03*
X691500D03*
X687560D03*
X683398Y1650134D03*
X697893Y41434D03*
X693954Y128011D03*
X707500Y396346D03*
X703500D03*
X695500D03*
X699500D03*
X707800Y525546D03*
X705742Y1395030D03*
X719950Y55029D03*
X714666Y94617D03*
X722666D03*
X718666D03*
X710666D03*
X714703Y383860D03*
X723500Y396346D03*
X721909Y528236D03*
X714845Y528408D03*
X711059Y1388707D03*
X721950Y1583842D03*
X721890Y1604721D03*
X709317Y1627270D03*
X713317Y1637770D03*
X717422Y1648821D03*
X713771Y1660449D03*
X715927Y1682188D03*
X721632Y1677367D03*
X737596Y55029D03*
X733643D03*
X724645D03*
X729294D03*
X735457Y383712D03*
X735500Y396346D03*
X731500D03*
X730152Y440328D03*
X736439Y500828D03*
X737610Y515138D03*
X738524Y1395130D03*
X727242Y1676553D03*
X749478Y55029D03*
X745475D03*
X741378D03*
X753036Y312729D03*
Y305729D03*
X747500Y383846D03*
X751500D03*
X743457Y383712D03*
X739457D03*
X743500Y396346D03*
X739652Y396328D03*
X751500Y396346D03*
X751972Y500940D03*
X744439Y500828D03*
X740439D03*
X748007Y501224D03*
X743841Y1388807D03*
X757038Y317244D03*
X755500Y396346D03*
X767500D03*
X760652Y500828D03*
X756652D03*
X764152D03*
X762350Y1584292D03*
X768500Y543346D03*
X781000Y569484D03*
X783974Y458862D03*
X785500Y532484D03*
X805450Y1587092D03*
X833445Y226202D03*
X847450Y1587092D03*
X862528Y267866D03*
X901000Y915484D03*
X889450Y1587092D03*
X917377Y884938D03*
X917000Y915484D03*
X916763Y989841D03*
X905487Y1141381D03*
X929603Y885405D03*
X918000Y924984D03*
X925500Y913484D03*
X929500Y922984D03*
X919500Y947984D03*
X946500Y913484D03*
X942500Y922984D03*
X938500Y913484D03*
X934500Y922984D03*
X932500Y947984D03*
X943798Y1666246D03*
X948000Y858484D03*
X949500Y876484D03*
X956500Y899484D03*
X961500D03*
X954500Y913484D03*
X950500Y922984D03*
X952512Y1141381D03*
X951798Y1658204D03*
X963500Y860484D03*
X967500Y1297484D03*
X1013306Y523630D03*
X1021911Y203112D03*
X1063968Y1332693D03*
X1075241Y1370679D03*
X1069924Y1377002D03*
X1107841Y1370679D03*
X1102524Y1377002D03*
X1122965Y1640287D03*
X1126000Y1678484D03*
X1140541Y1370679D03*
X1135224Y1377002D03*
X1129500Y1638484D03*
Y1678484D03*
X1147947Y1678889D03*
X1152000Y1678984D03*
X1168124Y1377002D03*
X1173441Y1370679D03*
X1190894Y1575196D03*
X1206241Y1370679D03*
X1200924Y1377002D03*
X1226094Y311625D03*
X1222094Y302625D03*
X1226094D03*
X1225934Y780366D03*
X1229934D03*
X1225500Y1411484D03*
X1244232Y1324533D03*
X1238915Y1330856D03*
X1231000Y1411484D03*
X1257177Y804308D03*
X1253177D03*
X1264177D03*
X1273177D03*
X1271811Y1330828D03*
X1277128Y1324505D03*
X1304715Y1330771D03*
X1291544Y1557106D03*
X1295544D03*
X1310032Y1324448D03*
X1318956Y1575196D03*
X1329477Y1218862D03*
X1348421Y1190111D03*
X1337977Y1218862D03*
X1342832Y1324648D03*
X1337515Y1330971D03*
X1352421Y1190111D03*
X1369677Y969472D03*
X1375414Y1343979D03*
X1370097Y1350302D03*
X1400063Y1009406D03*
X1403803D03*
X1407543D03*
X1405686Y1306242D03*
X1415024Y1009406D03*
X1422504D03*
X1411283D03*
X1418764D03*
X1417301Y1054749D03*
X1423606Y1557106D03*
X1419606D03*
X1426244Y1009406D03*
X1429984D03*
X1433724D03*
X1463177Y969472D03*
X1455068Y1575196D03*
X1469832Y540886D03*
X1475257Y543961D03*
X1481177Y808972D03*
X1474177Y822472D03*
X1498543Y585349D03*
X1494543D03*
X1493177Y808972D03*
X1485177D03*
X1486177Y822472D03*
X1490177D03*
X1510757Y570961D03*
X1502543Y585349D03*
X1504000Y808972D03*
X1502177Y822472D03*
X1535512Y1238415D03*
X1556111Y804171D03*
X1555718Y1557106D03*
X1559917Y804161D03*
X1565502Y1344668D03*
X1568906Y1359162D03*
X1559718Y1557106D03*
X1574000Y568484D03*
X1580924Y1351682D03*
X1581181Y1376357D03*
X1586000Y1376360D03*
X1578599Y1396916D03*
X1583411D03*
X1588099D03*
X1583130Y1575196D03*
X1595355Y800268D03*
X1590827Y1260338D03*
X1594827D03*
X1595438Y1376270D03*
X1590723Y1376350D03*
X1599657Y1376325D03*
X1592788Y1396916D03*
X1597674D03*
X1629826Y1424425D03*
X1658792Y1387996D03*
X1653475Y1394319D03*
X1691574Y1388096D03*
X1686257Y1394419D03*
X1689383Y1726652D03*
Y1719652D03*
X1693383Y1723502D03*
X1713173Y34228D03*
X1720462Y76589D03*
X1724462D03*
X1727429Y1675440D03*
X1731429D03*
X1741519Y1574569D03*
X1766062Y43087D03*
X1760929Y1654440D03*
X1769757Y34384D03*
X1774279Y1568089D03*
X1791645Y190881D03*
X1797994Y182503D03*
X1801979Y1533889D03*
G54D25*
X48575Y386993D03*
X48742Y393408D03*
X48828Y528304D03*
X48966Y533985D03*
X41117Y1598896D03*
X48151Y1625405D03*
X65412Y443677D03*
X55259Y1589981D03*
Y1585981D03*
X53617Y1612696D03*
X82117Y1625396D03*
Y1620896D03*
Y1616396D03*
X83843Y767766D03*
Y771366D03*
X90874Y960966D03*
X89984Y1417000D03*
Y1412500D03*
Y1408000D03*
Y1426000D03*
Y1421500D03*
Y1430500D03*
Y1440000D03*
X101143Y751766D03*
X103544Y767266D03*
X98984Y1412500D03*
Y1421500D03*
Y1426000D03*
Y1430500D03*
Y1440000D03*
Y1435500D03*
X113544Y767766D03*
Y771366D03*
X120575Y960966D03*
X129643Y751766D03*
X133245Y767266D03*
X133159Y1680513D03*
X143376Y767400D03*
Y771200D03*
X150275Y960966D03*
X159143Y751766D03*
X162884Y767266D03*
X173046Y767666D03*
Y771266D03*
X179976Y960966D03*
X200643Y751266D03*
X188643Y751766D03*
X192646Y767266D03*
X201165Y1652454D03*
Y1648454D03*
X202777Y767400D03*
X202746Y771366D03*
X209677Y960966D03*
X222247Y767266D03*
X232117Y583948D03*
X235347Y767766D03*
Y771366D03*
X251955Y772388D03*
Y776388D03*
X277755Y801888D03*
X285235Y804048D03*
X298625Y37420D03*
X348484Y578500D03*
Y582500D03*
X356641Y550415D03*
Y554415D03*
Y566415D03*
X365067Y590479D03*
X356641Y590415D03*
Y586415D03*
X361695Y1193918D03*
Y1187862D03*
X361755Y1202388D03*
X373415Y1199648D03*
X373375Y1211538D03*
X391255Y981766D03*
X389319Y978266D03*
X391755Y1000266D03*
Y987766D03*
X391655Y994488D03*
X391643Y1007266D03*
X389590Y1015474D03*
X389643Y1010766D03*
X389590Y1019017D03*
Y1022560D03*
X382755Y1207488D03*
X385701Y1677874D03*
X400641Y557415D03*
Y561415D03*
Y565415D03*
Y569415D03*
X400755Y966488D03*
X406255Y981766D03*
X400619Y978266D03*
X398755Y981766D03*
X399255Y987766D03*
X398655Y994488D03*
X406755Y987766D03*
X398655Y1000266D03*
X397143Y1010766D03*
X404643D03*
X410143Y1007266D03*
X397070Y1015474D03*
X404550D03*
X397070Y1019017D03*
X404550D03*
X409643Y1028266D03*
X397070Y1022560D03*
X404550D03*
X409643Y1034266D03*
X401755Y1071988D03*
X402484Y1626800D03*
X407490Y1631219D03*
X423255Y966488D03*
X423143Y978266D03*
X413755Y981766D03*
X421255D03*
X413755Y987766D03*
X420729Y987761D03*
X418650Y1006123D03*
Y1009864D03*
Y1013604D03*
Y1021084D03*
Y1028564D03*
Y1017344D03*
Y1024824D03*
X424143Y1060266D03*
X424255Y1071988D03*
X412960Y1610161D03*
X412987Y1615400D03*
X416984Y1657500D03*
X432785Y120209D03*
Y124209D03*
Y132297D03*
Y128297D03*
X428755Y981766D03*
X428100Y1014766D03*
X437925Y1014745D03*
Y1023013D03*
Y1018879D03*
X428082Y1023013D03*
Y1018879D03*
X439984Y1641500D03*
Y1646500D03*
X454755Y969988D03*
X441643Y989766D03*
X441568Y997766D03*
Y993766D03*
Y1001766D03*
X446783Y1014745D03*
Y1023013D03*
Y1018879D03*
X462516Y112039D03*
Y108039D03*
X467755Y966488D03*
X467143Y978266D03*
X457019Y1014745D03*
Y1023013D03*
Y1018879D03*
X468643Y1060266D03*
X455755Y1068488D03*
X468755Y1071988D03*
X481052Y281093D03*
X480143Y1060266D03*
X491482Y285893D03*
X490355Y1060288D03*
X514905Y124498D03*
X507410Y140498D03*
X508616Y157898D03*
Y153898D03*
X530075Y129207D03*
Y133207D03*
X547364Y144493D03*
Y148493D03*
Y160493D03*
Y164493D03*
Y156493D03*
Y152493D03*
X572045Y1234075D03*
X572065Y1238165D03*
X572841Y1252788D03*
X572085Y1245965D03*
Y1242105D03*
X564639Y1245927D03*
X584643Y1234075D03*
X576330Y1261913D03*
X591643Y1238075D03*
X605643Y1241575D03*
X616255Y1266988D03*
X616265Y1278668D03*
X622029Y55682D03*
X627079Y51682D03*
X625266Y65173D03*
X631117Y1368752D03*
X625104Y1388057D03*
X619700Y1379093D03*
X641206Y53747D03*
X641129Y70040D03*
Y66040D03*
X647328Y439518D03*
X646154Y461930D03*
X647401Y479141D03*
X648474Y751266D03*
X650923Y64745D03*
X650891Y68572D03*
X658788Y444497D03*
X659484Y457862D03*
Y469862D03*
Y465862D03*
X651813Y767266D03*
X662006Y767300D03*
Y771100D03*
X660451Y1641522D03*
X653451D03*
X657301Y1637522D03*
X669464Y210362D03*
Y206362D03*
Y202362D03*
X675482Y404646D03*
X675496Y413863D03*
X675505Y409222D03*
X675556Y422000D03*
X675509Y473362D03*
X677974Y751766D03*
X678556Y1684739D03*
X690984Y497000D03*
X681514Y767266D03*
X691707Y767300D03*
Y771100D03*
X680445Y1633042D03*
Y1637042D03*
X679881Y1650419D03*
X692454Y1662341D03*
X692457Y1658331D03*
X685394Y1684760D03*
X696536Y502534D03*
X707474Y751766D03*
X705742Y1631036D03*
X711215Y767266D03*
X721408Y767300D03*
Y771100D03*
X723234Y1590753D03*
X721176Y1628911D03*
Y1632961D03*
X732511Y582036D03*
X736974Y751766D03*
X728575Y1643997D03*
X752147Y76029D03*
X741984Y564000D03*
X742187Y569245D03*
X742040Y573171D03*
X751108Y767300D03*
X740916Y767266D03*
X751108Y771100D03*
X778136Y423344D03*
Y463344D03*
Y479344D03*
Y475344D03*
Y471344D03*
X780836Y483344D03*
X778436Y491644D03*
X778136Y499344D03*
Y495344D03*
X770736Y499344D03*
X770617Y767266D03*
X780809Y767300D03*
Y771100D03*
X793309Y456518D03*
Y460518D03*
X792636Y479344D03*
Y483344D03*
X788977Y487524D03*
X797379Y751765D03*
X797359Y1345923D03*
X802004Y144262D03*
Y139262D03*
X810048Y276820D03*
X810102Y284311D03*
X800875Y308062D03*
X809163Y504261D03*
X800317Y767266D03*
X804230Y1345878D03*
X826055Y288063D03*
X823328Y476159D03*
X814198Y1486876D03*
Y1490876D03*
Y1496876D03*
Y1500876D03*
Y1506284D03*
Y1516284D03*
Y1510284D03*
Y1520284D03*
X849966Y291559D03*
X852715Y301542D03*
X852874Y308852D03*
X852365Y1273971D03*
X852279Y1278139D03*
X852440Y1291468D03*
X852404Y1295981D03*
X857987Y273557D03*
X892691Y1145058D03*
X901067Y1268420D03*
X901111Y1272692D03*
X900986Y1281203D03*
X901034Y1276968D03*
X900777Y1298027D03*
X900738Y1293853D03*
X901010Y1289630D03*
X901032Y1285420D03*
X905484Y853000D03*
X915484Y945000D03*
X931409Y197612D03*
X925838Y1266347D03*
X925914Y1283048D03*
X926066Y1278713D03*
X925939Y1274591D03*
X925988Y1270408D03*
X926070Y1295957D03*
X925993Y1291676D03*
X926015Y1287193D03*
X921484Y1302000D03*
Y1306000D03*
X937984Y850500D03*
X944984Y894500D03*
X939716Y1145058D03*
X956984Y903500D03*
X960984Y1283000D03*
Y1287000D03*
X957007Y1505777D03*
Y1509777D03*
X997353Y1267126D03*
X1008324Y1275768D03*
X1008403Y1279751D03*
X1008353Y1271743D03*
X1014211Y1290096D03*
X1046785Y751265D03*
X1049924Y767265D03*
X1060116Y767299D03*
Y771099D03*
X1077285Y751765D03*
X1079625Y767265D03*
X1067016Y960965D03*
X1089817Y767299D03*
Y771099D03*
X1105785Y751765D03*
X1109325Y767265D03*
X1096717Y960965D03*
X1119518Y767299D03*
Y771099D03*
X1118198Y1649513D03*
X1135285Y751765D03*
X1139026Y767265D03*
X1126417Y960965D03*
X1136484Y1679000D03*
X1149219Y767299D03*
Y771099D03*
X1143580Y1673937D03*
X1164785Y751765D03*
X1168727Y767265D03*
X1156118Y960965D03*
X1176785Y751265D03*
X1178919Y767299D03*
Y771099D03*
X1198428Y767265D03*
X1185819Y960965D03*
X1190984Y1396500D03*
Y1401000D03*
X1199984D03*
X1190984Y1414500D03*
Y1405500D03*
Y1410000D03*
X1199984D03*
Y1414500D03*
Y1419000D03*
Y1424000D03*
X1211489Y767665D03*
Y771465D03*
X1296459Y134409D03*
X1307150Y537303D03*
X1336661Y1207988D03*
Y1211488D03*
X1355661Y1207988D03*
X1377161Y966488D03*
X1376761Y978265D03*
X1367661Y981765D03*
X1375161D03*
X1365461Y978265D03*
X1367661Y1000265D03*
X1375061D03*
X1367661Y987765D03*
X1374661Y994265D03*
X1367661D03*
X1375161Y987765D03*
X1373212Y1015473D03*
X1365785Y1010765D03*
X1373285D03*
X1365732Y1015473D03*
X1367785Y1007265D03*
X1365732Y1022559D03*
Y1019016D03*
X1373212D03*
Y1022559D03*
X1366661Y1060265D03*
X1369161Y1056765D03*
X1378161Y1071988D03*
X1382661Y981765D03*
X1390161D03*
X1389661Y987765D03*
X1382661D03*
X1380692Y1015473D03*
X1386285Y1007265D03*
X1380785Y1010765D03*
X1380692Y1019016D03*
Y1022559D03*
X1385785Y1028265D03*
Y1034265D03*
X1399161Y966488D03*
X1397661Y981765D03*
X1404661D03*
X1399285Y978265D03*
X1396861Y987765D03*
X1394792Y1013603D03*
Y1006122D03*
X1404224Y1014744D03*
X1394792Y1009863D03*
Y1017343D03*
Y1021083D03*
Y1024823D03*
X1404224Y1018878D03*
X1394792Y1028563D03*
X1404224Y1023012D03*
X1400285Y1060265D03*
X1400161Y1071988D03*
X1417710Y993765D03*
X1417785Y989765D03*
X1417710Y997765D03*
X1414067Y1014744D03*
X1422925D03*
X1417710Y1001765D03*
X1422925Y1018878D03*
X1414067Y1023012D03*
Y1018878D03*
X1422925Y1023012D03*
X1418153Y1641431D03*
X1411082Y1641405D03*
X1409873Y1649720D03*
X1416995Y1649716D03*
X1430661Y969988D03*
X1433161Y1014744D03*
Y1023012D03*
Y1018878D03*
X1431961Y1068488D03*
X1449011Y531318D03*
X1448511Y561318D03*
X1446771Y847652D03*
X1452787Y843652D03*
X1443661Y966488D03*
X1443285Y978265D03*
X1444785Y1060265D03*
X1444661Y1071988D03*
X1466585Y1060265D03*
X1469741Y544977D03*
Y556977D03*
X1479167Y581658D03*
X1469741Y580977D03*
Y576977D03*
Y568977D03*
Y572977D03*
X1513741Y547977D03*
Y551977D03*
Y555977D03*
Y559977D03*
X1531161Y797688D03*
Y801488D03*
X1567747Y1237662D03*
X1561161Y1234162D03*
X1562691Y1290418D03*
Y1293918D03*
X1570161Y1286108D03*
X1579287Y1235366D03*
X1586287Y1239866D03*
X1585431Y1264488D03*
Y1260588D03*
X1602661Y1282988D03*
Y1290988D03*
Y1298988D03*
Y1294988D03*
X1609030Y1307553D03*
X1624285Y752765D03*
X1627955Y767265D03*
X1638147D03*
Y771065D03*
X1653785Y753265D03*
X1657656Y767265D03*
X1667848D03*
Y771065D03*
X1690409Y118762D03*
X1680759Y131762D03*
X1690409D03*
Y126762D03*
Y122762D03*
X1680759Y136762D03*
X1690409Y141762D03*
Y136762D03*
Y149762D03*
Y145762D03*
Y157762D03*
Y166762D03*
X1684785Y753265D03*
X1687357Y767265D03*
X1697549D03*
Y771065D03*
X1716247Y43654D03*
Y39654D03*
Y51654D03*
Y47654D03*
X1713285Y752765D03*
X1717058Y767265D03*
X1727250Y767299D03*
Y771099D03*
X1729913Y1654456D03*
Y1681456D03*
X1742785Y752765D03*
X1746759Y767265D03*
X1756950Y767305D03*
Y771105D03*
X1772785Y753265D03*
X1776459Y767265D03*
X1772349Y1669037D03*
X1770947Y1661465D03*
X1771147Y1672965D03*
X1786651Y767565D03*
Y771365D03*
X1814106Y170869D03*
G54D109*
X909994Y929426D03*
G54D61*
X415174Y105712D03*
Y113192D03*
X455534Y138539D03*
Y146019D03*
G54D118*
X1474107Y563127D03*
G54D43*
X230905Y1734212D03*
X297835D03*
X495078D03*
X562008D03*
X1238778D03*
X1305708D03*
X1502952D03*
X1569882D03*
G54D52*
X373673Y-28871D03*
Y-18871D03*
D03*
Y-8871D03*
X398673Y-28871D03*
Y-18871D03*
D03*
Y-8871D03*
X718093Y-28871D03*
Y-18871D03*
D03*
Y-8871D03*
X743093Y-28871D03*
Y-18871D03*
D03*
Y-8871D03*
X825152Y-35011D03*
Y-25011D03*
Y-15011D03*
Y-25011D03*
Y-15011D03*
Y-5011D03*
D03*
Y4989D03*
Y14989D03*
D03*
Y4989D03*
Y24989D03*
X850152Y-35011D03*
Y-25011D03*
Y-15011D03*
Y-25011D03*
Y-15011D03*
Y-5011D03*
D03*
Y4989D03*
Y14989D03*
D03*
Y4989D03*
Y24989D03*
X1169572Y-35011D03*
Y-15011D03*
Y-25011D03*
D03*
Y-15011D03*
Y-5011D03*
D03*
Y4989D03*
Y14989D03*
Y4989D03*
Y14989D03*
Y24989D03*
X1194572Y-35011D03*
Y-15011D03*
Y-25011D03*
D03*
Y-15011D03*
Y-5011D03*
D03*
Y4989D03*
Y14989D03*
Y4989D03*
Y14989D03*
Y24989D03*
X1228672Y-35011D03*
Y-25011D03*
Y-15011D03*
Y-25011D03*
Y-15011D03*
Y-5011D03*
D03*
Y4989D03*
Y14989D03*
D03*
Y4989D03*
Y24989D03*
X1253672Y-35011D03*
Y-25011D03*
Y-15011D03*
Y-25011D03*
Y-15011D03*
Y-5011D03*
D03*
Y4989D03*
Y14989D03*
D03*
Y4989D03*
Y24989D03*
X1428431Y-35011D03*
Y-15011D03*
Y-25011D03*
D03*
Y-15011D03*
Y-5011D03*
D03*
Y4989D03*
Y14989D03*
Y4989D03*
Y14989D03*
Y24989D03*
X1453431Y-35011D03*
Y-15011D03*
Y-25011D03*
D03*
Y-15011D03*
Y-5011D03*
D03*
Y4989D03*
Y14989D03*
Y4989D03*
Y14989D03*
Y24989D03*
X1521966Y-29212D03*
D03*
Y-39212D03*
Y-19212D03*
X1546966Y-29212D03*
D03*
Y-39212D03*
Y-19212D03*
X1721725Y-29212D03*
Y-39212D03*
Y-29212D03*
Y-19212D03*
X1746725Y-29212D03*
Y-39212D03*
Y-29212D03*
Y-19212D03*
G54D70*
X539016Y274272D03*
X549016D03*
X559016D03*
X569016D03*
X579016D03*
X589016D03*
X599016D03*
G54D34*
X77394Y734588D03*
Y1021399D03*
Y1277698D03*
X107095Y734588D03*
Y1021399D03*
Y1277698D03*
X136795Y734588D03*
Y1021399D03*
Y1277698D03*
X166496Y734588D03*
Y1021399D03*
Y1277698D03*
X196197Y734588D03*
Y1021399D03*
Y1277698D03*
X225898Y734588D03*
Y1021399D03*
Y1277698D03*
X655425Y734588D03*
Y1021399D03*
Y1277698D03*
X685126Y734588D03*
Y1021399D03*
Y1277698D03*
X714827Y734588D03*
Y1021399D03*
Y1277698D03*
X744528Y734588D03*
Y1021399D03*
Y1277698D03*
X774229Y734588D03*
Y1021399D03*
Y1277698D03*
X803929Y734588D03*
Y1021399D03*
Y1277698D03*
X1053536Y734587D03*
Y1021398D03*
Y1277697D03*
X1083237Y734587D03*
Y1021398D03*
Y1277697D03*
X1112937Y734587D03*
Y1021398D03*
Y1277697D03*
X1142638Y734587D03*
Y1021398D03*
Y1277697D03*
X1172339Y734587D03*
Y1021398D03*
Y1277697D03*
X1202040Y734587D03*
Y1021398D03*
Y1277697D03*
X1631567Y734587D03*
Y1021398D03*
Y1277697D03*
X1661268Y734587D03*
Y1021398D03*
Y1277697D03*
X1690969Y734587D03*
Y1021398D03*
Y1277697D03*
X1720670Y734587D03*
Y1021398D03*
Y1277697D03*
X1750371Y734587D03*
Y1021398D03*
Y1277697D03*
X1780071Y734587D03*
Y1021398D03*
Y1277697D03*
G54D128*
G01X-476840Y-884638D02*
Y2768362D01*
X5911000D01*
Y-884638D01*
X-476840D01*
G01X8000Y-625138D02*
Y-630138D01*
G01X6543Y-625138D02*
X9457D01*
G01X14367Y-630138D02*
X11833D01*
Y-625138D01*
X14367D01*
G01X13353Y-627555D02*
X11833D01*
G01X16933Y-625138D02*
Y-630138D01*
X19467D01*
G01X23300Y-630305D02*
X23173Y-630221D01*
Y-630055D01*
X23300Y-629971D01*
X23427Y-630055D01*
Y-630221D01*
X23300Y-630305D01*
G01Y-628055D02*
X23173Y-627971D01*
Y-627805D01*
X23300Y-627721D01*
X23427Y-627805D01*
Y-627971D01*
X23300Y-628055D01*
G01X28083Y-631805D02*
X27450Y-630971D01*
X27133Y-630138D01*
Y-626805D01*
X27450Y-625971D01*
X28083Y-625138D01*
G01X33500D02*
X32993Y-625305D01*
X32613Y-625721D01*
X32360Y-626221D01*
X32170Y-626888D01*
X32107Y-627638D01*
X32170Y-628388D01*
X32360Y-629055D01*
X32613Y-629555D01*
X32993Y-629971D01*
X33500Y-630138D01*
X34007Y-629971D01*
X34387Y-629555D01*
X34640Y-629055D01*
X34830Y-628388D01*
X34893Y-627638D01*
X34830Y-626888D01*
X34640Y-626221D01*
X34387Y-625721D01*
X34007Y-625305D01*
X33500Y-625138D01*
G01X37207Y-629138D02*
X37587Y-629721D01*
X38093Y-630055D01*
X38663Y-630138D01*
X39170Y-630055D01*
X39677Y-629638D01*
X39993Y-629138D01*
X40057Y-628638D01*
X39930Y-628055D01*
X39487Y-627638D01*
X39043Y-627471D01*
X38473D01*
G01X39043D02*
X39423Y-627221D01*
X39740Y-626805D01*
X39867Y-626305D01*
X39740Y-625805D01*
X39423Y-625388D01*
X38853Y-625138D01*
X38283Y-625221D01*
X37713Y-625555D01*
G01X44017Y-631805D02*
X44650Y-630971D01*
X44967Y-630138D01*
Y-626805D01*
X44650Y-625971D01*
X44017Y-625138D01*
G01X47407Y-629138D02*
X47787Y-629721D01*
X48293Y-630055D01*
X48863Y-630138D01*
X49370Y-630055D01*
X49877Y-629638D01*
X50193Y-629138D01*
X50257Y-628638D01*
X50130Y-628055D01*
X49687Y-627638D01*
X49243Y-627471D01*
X48673D01*
G01X49243D02*
X49623Y-627221D01*
X49940Y-626805D01*
X50067Y-626305D01*
X49940Y-625805D01*
X49623Y-625388D01*
X49053Y-625138D01*
X48483Y-625221D01*
X47913Y-625555D01*
G01X52697Y-625971D02*
X53077Y-625471D01*
X53520Y-625221D01*
X54027Y-625138D01*
X54660Y-625305D01*
X55103Y-625721D01*
X55230Y-626221D01*
X55167Y-626721D01*
X54913Y-627138D01*
X53647Y-627971D01*
X53077Y-628555D01*
X52697Y-629388D01*
X52570Y-630138D01*
X55230D01*
G01X58873D02*
X59000Y-629055D01*
X59190Y-628138D01*
X59443Y-627305D01*
X59760Y-626388D01*
X60267Y-625138D01*
X57733D01*
G01X63277Y-628471D02*
X64923D01*
G01X67997Y-625971D02*
X68377Y-625471D01*
X68820Y-625221D01*
X69327Y-625138D01*
X69960Y-625305D01*
X70403Y-625721D01*
X70530Y-626221D01*
X70467Y-626721D01*
X70213Y-627138D01*
X68947Y-627971D01*
X68377Y-628555D01*
X67997Y-629388D01*
X67870Y-630138D01*
X70530D01*
G01X72907Y-629138D02*
X73287Y-629721D01*
X73793Y-630055D01*
X74363Y-630138D01*
X74870Y-630055D01*
X75377Y-629638D01*
X75693Y-629138D01*
X75757Y-628638D01*
X75630Y-628055D01*
X75187Y-627638D01*
X74743Y-627471D01*
X74173D01*
G01X74743D02*
X75123Y-627221D01*
X75440Y-626805D01*
X75567Y-626305D01*
X75440Y-625805D01*
X75123Y-625388D01*
X74553Y-625138D01*
X73983Y-625221D01*
X73413Y-625555D01*
G01X80160Y-630138D02*
Y-625138D01*
X77817Y-628721D01*
X80983D01*
G01X83107Y-629388D02*
X83487Y-629805D01*
X83930Y-630055D01*
X84500Y-630138D01*
X85070Y-629971D01*
X85513Y-629638D01*
X85830Y-629055D01*
X85893Y-628388D01*
X85767Y-627721D01*
X85450Y-627305D01*
X85007Y-626971D01*
X84563Y-626888D01*
X84120Y-626971D01*
X83550Y-627305D01*
X83740Y-625138D01*
X85450D01*
G01X93497Y-630138D02*
Y-625138D01*
X95903D01*
G01X95017Y-627555D02*
X93497D01*
G01X98217Y-630138D02*
X99800Y-625138D01*
X101383Y-630138D01*
G01X100813Y-628388D02*
X98787D01*
G01X103570Y-630138D02*
X106230Y-625138D01*
G01X103570D02*
X106230Y-630138D01*
G01X110000Y-630305D02*
X109873Y-630221D01*
Y-630055D01*
X110000Y-629971D01*
X110127Y-630055D01*
Y-630221D01*
X110000Y-630305D01*
G01Y-628055D02*
X109873Y-627971D01*
Y-627805D01*
X110000Y-627721D01*
X110127Y-627805D01*
Y-627971D01*
X110000Y-628055D01*
G01X114783Y-631805D02*
X114150Y-630971D01*
X113833Y-630138D01*
Y-626805D01*
X114150Y-625971D01*
X114783Y-625138D01*
G01X120200D02*
X119693Y-625305D01*
X119313Y-625721D01*
X119060Y-626221D01*
X118870Y-626888D01*
X118807Y-627638D01*
X118870Y-628388D01*
X119060Y-629055D01*
X119313Y-629555D01*
X119693Y-629971D01*
X120200Y-630138D01*
X120707Y-629971D01*
X121087Y-629555D01*
X121340Y-629055D01*
X121530Y-628388D01*
X121593Y-627638D01*
X121530Y-626888D01*
X121340Y-626221D01*
X121087Y-625721D01*
X120707Y-625305D01*
X120200Y-625138D01*
G01X123907Y-629138D02*
X124287Y-629721D01*
X124793Y-630055D01*
X125363Y-630138D01*
X125870Y-630055D01*
X126377Y-629638D01*
X126693Y-629138D01*
X126757Y-628638D01*
X126630Y-628055D01*
X126187Y-627638D01*
X125743Y-627471D01*
X125173D01*
G01X125743D02*
X126123Y-627221D01*
X126440Y-626805D01*
X126567Y-626305D01*
X126440Y-625805D01*
X126123Y-625388D01*
X125553Y-625138D01*
X124983Y-625221D01*
X124413Y-625555D01*
G01X130717Y-631805D02*
X131350Y-630971D01*
X131667Y-630138D01*
Y-626805D01*
X131350Y-625971D01*
X130717Y-625138D01*
G01X134107Y-629138D02*
X134487Y-629721D01*
X134993Y-630055D01*
X135563Y-630138D01*
X136070Y-630055D01*
X136577Y-629638D01*
X136893Y-629138D01*
X136957Y-628638D01*
X136830Y-628055D01*
X136387Y-627638D01*
X135943Y-627471D01*
X135373D01*
G01X135943D02*
X136323Y-627221D01*
X136640Y-626805D01*
X136767Y-626305D01*
X136640Y-625805D01*
X136323Y-625388D01*
X135753Y-625138D01*
X135183Y-625221D01*
X134613Y-625555D01*
G01X139523Y-629555D02*
X139967Y-629971D01*
X140473Y-630138D01*
X140980Y-629971D01*
X141423Y-629471D01*
X141740Y-628721D01*
X141867Y-627971D01*
Y-627055D01*
X141740Y-626305D01*
X141423Y-625638D01*
X141043Y-625305D01*
X140600Y-625138D01*
X140093Y-625305D01*
X139713Y-625638D01*
X139460Y-626138D01*
X139333Y-626805D01*
X139460Y-627388D01*
X139777Y-627971D01*
X140157Y-628305D01*
X140600Y-628388D01*
X141107Y-628221D01*
X141487Y-627805D01*
X141867Y-627055D01*
G01X145573Y-630138D02*
X145700Y-629055D01*
X145890Y-628138D01*
X146143Y-627305D01*
X146460Y-626388D01*
X146967Y-625138D01*
X144433D01*
G01X149977Y-628471D02*
X151623D01*
G01X154507Y-629138D02*
X154887Y-629721D01*
X155393Y-630055D01*
X155963Y-630138D01*
X156470Y-630055D01*
X156977Y-629638D01*
X157293Y-629138D01*
X157357Y-628638D01*
X157230Y-628055D01*
X156787Y-627638D01*
X156343Y-627471D01*
X155773D01*
G01X156343D02*
X156723Y-627221D01*
X157040Y-626805D01*
X157167Y-626305D01*
X157040Y-625805D01*
X156723Y-625388D01*
X156153Y-625138D01*
X155583Y-625221D01*
X155013Y-625555D01*
G01X159797Y-628055D02*
X160240Y-627471D01*
X160620Y-627138D01*
X161127Y-626971D01*
X161570Y-627138D01*
X161887Y-627471D01*
X162140Y-627971D01*
X162203Y-628555D01*
X162140Y-629055D01*
X161887Y-629555D01*
X161507Y-629971D01*
X161063Y-630138D01*
X160557Y-629971D01*
X160113Y-629471D01*
X159860Y-628721D01*
X159797Y-627888D01*
X159923Y-626805D01*
X160113Y-626221D01*
X160430Y-625638D01*
X160873Y-625221D01*
X161317Y-625138D01*
X161760Y-625305D01*
X162077Y-625721D01*
G01X166100Y-630138D02*
Y-625138D01*
X165340Y-626138D01*
G01Y-630138D02*
X166860D01*
G01X171960D02*
Y-625138D01*
X169617Y-628721D01*
X172783D01*
G01X-4000Y-560138D02*
Y-635138D01*
X496000D01*
Y-560138D01*
X-4000D01*
G01X191000D02*
Y-635138D01*
G01Y-610138D02*
X294000D01*
Y-585138D01*
G01X191000D02*
X294000D01*
G01X296000Y-560138D02*
Y-635138D01*
G01X294000Y-560138D02*
Y-635138D01*
G01X301507Y-620138D02*
Y-615138D01*
X302773D01*
X303280Y-615388D01*
X303660Y-615721D01*
X303977Y-616221D01*
X304230Y-616805D01*
X304293Y-617638D01*
X304230Y-618471D01*
X303977Y-619055D01*
X303660Y-619555D01*
X303280Y-619888D01*
X302773Y-620138D01*
X301507D01*
G01X306417D02*
X308000Y-615138D01*
X309583Y-620138D01*
G01X309013Y-618388D02*
X306987D01*
G01X313100Y-615138D02*
Y-620138D01*
G01X311643Y-615138D02*
X314557D01*
G01X319467Y-620138D02*
X316933D01*
Y-615138D01*
X319467D01*
G01X318453Y-617555D02*
X316933D01*
G01X323300Y-620305D02*
X323173Y-620221D01*
Y-620055D01*
X323300Y-619971D01*
X323427Y-620055D01*
Y-620221D01*
X323300Y-620305D01*
G01Y-618055D02*
X323173Y-617971D01*
Y-617805D01*
X323300Y-617721D01*
X323427Y-617805D01*
Y-617971D01*
X323300Y-618055D01*
G01X296000Y-610138D02*
X496000D01*
G01X301633Y-595138D02*
Y-590138D01*
X303153D01*
X303660Y-590388D01*
X304040Y-590971D01*
X304167Y-591638D01*
X304040Y-592305D01*
X303723Y-592805D01*
X303153Y-593055D01*
X301633D01*
G01X306860Y-595305D02*
X309140Y-590138D01*
G01X311643Y-595138D02*
Y-590138D01*
X314557Y-595138D01*
Y-590138D01*
G01X318200Y-595305D02*
X318073Y-595221D01*
Y-595055D01*
X318200Y-594971D01*
X318327Y-595055D01*
Y-595221D01*
X318200Y-595305D01*
G01Y-593055D02*
X318073Y-592971D01*
Y-592805D01*
X318200Y-592721D01*
X318327Y-592805D01*
Y-592971D01*
X318200Y-593055D01*
G01X296000Y-585138D02*
X496000D01*
G01X301633Y-570138D02*
Y-565138D01*
X303153D01*
X303660Y-565388D01*
X304040Y-565971D01*
X304167Y-566638D01*
X304040Y-567305D01*
X303723Y-567805D01*
X303153Y-568055D01*
X301633D01*
G01X306733Y-570138D02*
Y-565138D01*
X308317D01*
X308823Y-565388D01*
X309140Y-565721D01*
X309267Y-566388D01*
X309140Y-567055D01*
X308760Y-567471D01*
X308317Y-567721D01*
X306733D01*
G01X308317D02*
X309267Y-570138D01*
G01X313100D02*
X312593Y-570055D01*
X312150Y-569721D01*
X311770Y-569221D01*
X311517Y-568638D01*
X311390Y-567971D01*
Y-567305D01*
X311517Y-566638D01*
X311770Y-566055D01*
X312150Y-565555D01*
X312593Y-565221D01*
X313100Y-565138D01*
X313607Y-565221D01*
X314050Y-565555D01*
X314430Y-566055D01*
X314683Y-566638D01*
X314810Y-567305D01*
Y-567971D01*
X314683Y-568638D01*
X314430Y-569221D01*
X314050Y-569721D01*
X313607Y-570055D01*
X313100Y-570138D01*
G01X316933Y-569138D02*
X317250Y-569638D01*
X317630Y-569971D01*
X318073Y-570138D01*
X318580Y-569971D01*
X318960Y-569638D01*
X319340Y-569138D01*
X319467Y-568471D01*
Y-565138D01*
G01X324567Y-570138D02*
X322033D01*
Y-565138D01*
X324567D01*
G01X323553Y-567555D02*
X322033D01*
G01X329793Y-565555D02*
X329413Y-565305D01*
X328970Y-565138D01*
X328463D01*
X327893Y-565388D01*
X327450Y-565805D01*
X327133Y-566305D01*
X326880Y-567138D01*
X326817Y-567888D01*
X326943Y-568638D01*
X327133Y-569138D01*
X327513Y-569638D01*
X327957Y-569971D01*
X328400Y-570138D01*
X328843D01*
X329287Y-569971D01*
X329667Y-569721D01*
X329983Y-569388D01*
G01X333500Y-565138D02*
Y-570138D01*
G01X332043Y-565138D02*
X334957D01*
G01X338600Y-570305D02*
X338473Y-570221D01*
Y-570055D01*
X338600Y-569971D01*
X338727Y-570055D01*
Y-570221D01*
X338600Y-570305D01*
G01Y-568055D02*
X338473Y-567971D01*
Y-567805D01*
X338600Y-567721D01*
X338727Y-567805D01*
Y-567971D01*
X338600Y-568055D01*
G01X411000Y-610138D02*
Y-635138D01*
G01X413633Y-612638D02*
Y-617638D01*
X416167D01*
G01X419240Y-612638D02*
X420760D01*
G01X420000D02*
Y-617638D01*
G01X419240D02*
X420760D01*
G01X425607Y-614971D02*
X425860Y-614721D01*
X426050Y-614305D01*
X426177Y-613721D01*
X426050Y-613221D01*
X425797Y-612888D01*
X425353Y-612638D01*
X423643D01*
Y-617638D01*
X425733D01*
X426177Y-617305D01*
X426430Y-616805D01*
X426557Y-616221D01*
X426430Y-615638D01*
X426050Y-615138D01*
X425607Y-614971D01*
X423643D01*
G01X430200Y-617805D02*
X430073Y-617721D01*
Y-617555D01*
X430200Y-617471D01*
X430327Y-617555D01*
Y-617721D01*
X430200Y-617805D01*
G01Y-615555D02*
X430073Y-615471D01*
Y-615305D01*
X430200Y-615221D01*
X430327Y-615305D01*
Y-615471D01*
X430200Y-615555D01*
G01X454000Y-610138D02*
Y-635138D01*
G01Y-585138D02*
Y-610138D01*
G01X459013Y-637305D02*
X459120Y-637180D01*
X459200Y-636971D01*
X459253Y-636680D01*
X459200Y-636430D01*
X459093Y-636263D01*
X458907Y-636138D01*
X458187D01*
Y-638638D01*
X459067D01*
X459253Y-638471D01*
X459360Y-638221D01*
X459413Y-637930D01*
X459360Y-637638D01*
X459200Y-637388D01*
X459013Y-637305D01*
X458187D01*
G01X461480Y-638638D02*
Y-636971D01*
G01Y-637263D02*
X461373Y-637096D01*
X461213Y-637013D01*
X461027Y-636971D01*
X460840Y-637055D01*
X460680Y-637221D01*
X460573Y-637471D01*
X460520Y-637805D01*
X460573Y-638138D01*
X460680Y-638388D01*
X460840Y-638555D01*
X461027Y-638638D01*
X461213Y-638596D01*
X461373Y-638471D01*
X461480Y-638305D01*
G01X462800Y-638346D02*
X462933Y-638513D01*
X463120Y-638638D01*
X463280D01*
X463440Y-638555D01*
X463547Y-638430D01*
X463600Y-638263D01*
X463573Y-638013D01*
X463467Y-637888D01*
X462987Y-637638D01*
X462880Y-637346D01*
X462933Y-637138D01*
X463040Y-637013D01*
X463200Y-636971D01*
X463360Y-637013D01*
X463520Y-637138D01*
G01X465000Y-637513D02*
X465853D01*
X465773Y-637221D01*
X465640Y-637055D01*
X465453Y-636971D01*
X465267Y-637013D01*
X465107Y-637138D01*
X465000Y-637430D01*
X464947Y-637680D01*
Y-637930D01*
X465000Y-638180D01*
X465133Y-638430D01*
X465293Y-638596D01*
X465480Y-638638D01*
X465667Y-638555D01*
X465853Y-638305D01*
G01X467120Y-638638D02*
Y-636138D01*
G01Y-637388D02*
X467253Y-637138D01*
X467413Y-637013D01*
X467573Y-636971D01*
X467813Y-637055D01*
X467973Y-637221D01*
X468080Y-637513D01*
Y-637846D01*
X468027Y-638180D01*
X467920Y-638430D01*
X467733Y-638596D01*
X467573Y-638638D01*
X467413Y-638596D01*
X467253Y-638471D01*
X467120Y-638263D01*
G01X469800Y-638638D02*
X469640Y-638596D01*
X469480Y-638430D01*
X469373Y-638138D01*
X469320Y-637805D01*
X469373Y-637471D01*
X469480Y-637180D01*
X469640Y-637013D01*
X469800Y-636971D01*
X469960Y-637013D01*
X470120Y-637180D01*
X470227Y-637471D01*
X470253Y-637805D01*
X470227Y-638138D01*
X470120Y-638430D01*
X469960Y-638596D01*
X469800Y-638638D01*
G01X472480D02*
Y-636971D01*
G01Y-637263D02*
X472373Y-637096D01*
X472213Y-637013D01*
X472027Y-636971D01*
X471840Y-637055D01*
X471680Y-637221D01*
X471573Y-637471D01*
X471520Y-637805D01*
X471573Y-638138D01*
X471680Y-638388D01*
X471840Y-638555D01*
X472027Y-638638D01*
X472213Y-638596D01*
X472373Y-638471D01*
X472480Y-638305D01*
G01X473827Y-638638D02*
Y-636971D01*
G01Y-637305D02*
X473960Y-637138D01*
X474093Y-637013D01*
X474280Y-636971D01*
X474413Y-637013D01*
X474573Y-637138D01*
G01X476880Y-636138D02*
Y-638638D01*
G01Y-638263D02*
X476773Y-638471D01*
X476613Y-638596D01*
X476427Y-638638D01*
X476213Y-638555D01*
X476053Y-638346D01*
X475947Y-638096D01*
X475920Y-637805D01*
X475947Y-637513D01*
X476053Y-637263D01*
X476213Y-637055D01*
X476427Y-636971D01*
X476613Y-637013D01*
X476747Y-637096D01*
X476880Y-637263D01*
G01X480267Y-638638D02*
Y-636138D01*
X480933D01*
X481147Y-636263D01*
X481280Y-636430D01*
X481333Y-636763D01*
X481280Y-637096D01*
X481120Y-637305D01*
X480933Y-637430D01*
X480267D01*
G01X480933D02*
X481333Y-638638D01*
G01X482600Y-637513D02*
X483453D01*
X483373Y-637221D01*
X483240Y-637055D01*
X483053Y-636971D01*
X482867Y-637013D01*
X482707Y-637138D01*
X482600Y-637430D01*
X482547Y-637680D01*
Y-637930D01*
X482600Y-638180D01*
X482733Y-638430D01*
X482893Y-638596D01*
X483080Y-638638D01*
X483267Y-638555D01*
X483453Y-638305D01*
G01X484720Y-636971D02*
X485200Y-638638D01*
X485680Y-636971D01*
G01X487400Y-638721D02*
X487347Y-638680D01*
Y-638596D01*
X487400Y-638555D01*
X487453Y-638596D01*
Y-638680D01*
X487400Y-638721D01*
G01X489147Y-638346D02*
X489333Y-638555D01*
X489547Y-638638D01*
X489760Y-638555D01*
X489947Y-638305D01*
X490080Y-637930D01*
X490133Y-637555D01*
Y-637096D01*
X490080Y-636721D01*
X489947Y-636388D01*
X489787Y-636221D01*
X489600Y-636138D01*
X489387Y-636221D01*
X489227Y-636388D01*
X489120Y-636638D01*
X489067Y-636971D01*
X489120Y-637263D01*
X489253Y-637555D01*
X489413Y-637721D01*
X489600Y-637763D01*
X489813Y-637680D01*
X489973Y-637471D01*
X490133Y-637096D01*
G01X492013Y-637305D02*
X492120Y-637180D01*
X492200Y-636971D01*
X492253Y-636680D01*
X492200Y-636430D01*
X492093Y-636263D01*
X491907Y-636138D01*
X491187D01*
Y-638638D01*
X492067D01*
X492253Y-638471D01*
X492360Y-638221D01*
X492413Y-637930D01*
X492360Y-637638D01*
X492200Y-637388D01*
X492013Y-637305D01*
X491187D01*
G01X457900Y-612638D02*
Y-617638D01*
G01X456443Y-612638D02*
X459357D01*
G01X463000Y-617638D02*
X462620Y-617555D01*
X462240Y-617221D01*
X461987Y-616638D01*
X461860Y-615971D01*
X461987Y-615305D01*
X462240Y-614721D01*
X462620Y-614388D01*
X463000Y-614305D01*
X463380Y-614388D01*
X463760Y-614721D01*
X464013Y-615305D01*
X464077Y-615971D01*
X464013Y-616638D01*
X463760Y-617221D01*
X463380Y-617555D01*
X463000Y-617638D01*
G01X468100D02*
X467720Y-617555D01*
X467340Y-617221D01*
X467087Y-616638D01*
X466960Y-615971D01*
X467087Y-615305D01*
X467340Y-614721D01*
X467720Y-614388D01*
X468100Y-614305D01*
X468480Y-614388D01*
X468860Y-614721D01*
X469113Y-615305D01*
X469177Y-615971D01*
X469113Y-616638D01*
X468860Y-617221D01*
X468480Y-617555D01*
X468100Y-617638D01*
G01X473200D02*
Y-612638D01*
G01X478300Y-617805D02*
X478173Y-617721D01*
Y-617555D01*
X478300Y-617471D01*
X478427Y-617555D01*
Y-617721D01*
X478300Y-617805D01*
G01Y-615555D02*
X478173Y-615471D01*
Y-615305D01*
X478300Y-615221D01*
X478427Y-615305D01*
Y-615471D01*
X478300Y-615555D01*
G01X456633Y-592638D02*
Y-587638D01*
X458217D01*
X458723Y-587888D01*
X459040Y-588221D01*
X459167Y-588888D01*
X459040Y-589555D01*
X458660Y-589971D01*
X458217Y-590221D01*
X456633D01*
G01X458217D02*
X459167Y-592638D01*
G01X464267D02*
X461733D01*
Y-587638D01*
X464267D01*
G01X463253Y-590055D02*
X461733D01*
G01X466517Y-587638D02*
X468100Y-592638D01*
X469683Y-587638D01*
G01X473200Y-592805D02*
X473073Y-592721D01*
Y-592555D01*
X473200Y-592471D01*
X473327Y-592555D01*
Y-592721D01*
X473200Y-592805D01*
G01Y-590555D02*
X473073Y-590471D01*
Y-590305D01*
X473200Y-590221D01*
X473327Y-590305D01*
Y-590471D01*
X473200Y-590555D01*
G01X-476840Y-884638D02*
Y2768362D01*
X5911000D01*
Y-884638D01*
X-476840D01*
G01X8820Y-607488D02*
X10387D01*
Y-609378D01*
X9917Y-610008D01*
X9368Y-610428D01*
X8585Y-610638D01*
X7802Y-610428D01*
X7253Y-610008D01*
X6783Y-609378D01*
X6470Y-608643D01*
X6313Y-607803D01*
Y-607068D01*
X6470Y-606438D01*
X6783Y-605703D01*
X7253Y-605073D01*
X7723Y-604653D01*
X8350Y-604338D01*
X8898D01*
X9525Y-604548D01*
X9995Y-604968D01*
G01X12927Y-604338D02*
Y-608853D01*
X13240Y-609798D01*
X13867Y-610428D01*
X14650Y-610638D01*
X15433Y-610428D01*
X16060Y-609798D01*
X16373Y-608853D01*
Y-604338D01*
G01X20010D02*
X21890D01*
G01X20950D02*
Y-610638D01*
G01X20010D02*
X21890D01*
G01X25605Y-609798D02*
X26232Y-610323D01*
X26937Y-610638D01*
X27563D01*
X28190Y-610323D01*
X28660Y-609798D01*
X28895Y-609063D01*
X28738Y-608328D01*
X28347Y-607698D01*
X27642Y-607278D01*
X26702Y-607068D01*
X26153Y-606648D01*
X25918Y-605913D01*
X26075Y-605178D01*
X26467Y-604653D01*
X27015Y-604338D01*
X27563D01*
X28112Y-604548D01*
X28582Y-605073D01*
G01X31905Y-610638D02*
Y-604338D01*
G01X35195D02*
Y-610638D01*
G01Y-607488D02*
X31905D01*
G01X37892Y-610638D02*
X39850Y-604338D01*
X41808Y-610638D01*
G01X41103Y-608433D02*
X38597D01*
G01X44348Y-610638D02*
Y-604338D01*
X47952Y-610638D01*
Y-604338D01*
G01X57027Y-610638D02*
Y-604338D01*
X58593D01*
X59220Y-604653D01*
X59690Y-605073D01*
X60082Y-605703D01*
X60395Y-606438D01*
X60473Y-607488D01*
X60395Y-608538D01*
X60082Y-609273D01*
X59690Y-609903D01*
X59220Y-610323D01*
X58593Y-610638D01*
X57027D01*
G01X64110Y-604338D02*
X65990D01*
G01X65050D02*
Y-610638D01*
G01X64110D02*
X65990D01*
G01X69705Y-609798D02*
X70332Y-610323D01*
X71037Y-610638D01*
X71663D01*
X72290Y-610323D01*
X72760Y-609798D01*
X72995Y-609063D01*
X72838Y-608328D01*
X72447Y-607698D01*
X71742Y-607278D01*
X70802Y-607068D01*
X70253Y-606648D01*
X70018Y-605913D01*
X70175Y-605178D01*
X70567Y-604653D01*
X71115Y-604338D01*
X71663D01*
X72212Y-604548D01*
X72682Y-605073D01*
G01X77650Y-604338D02*
Y-610638D01*
G01X75848Y-604338D02*
X79452D01*
G01X83950Y-610848D02*
X83793Y-610743D01*
Y-610533D01*
X83950Y-610428D01*
X84107Y-610533D01*
Y-610743D01*
X83950Y-610848D01*
G01X90093Y-611793D02*
X90407Y-610428D01*
G01X96550Y-604338D02*
Y-610638D01*
G01X94748Y-604338D02*
X98352D01*
G01X100892Y-610638D02*
X102850Y-604338D01*
X104808Y-610638D01*
G01X104103Y-608433D02*
X101597D01*
G01X109150Y-610638D02*
X108523Y-610533D01*
X107975Y-610113D01*
X107505Y-609483D01*
X107192Y-608748D01*
X107035Y-607908D01*
Y-607068D01*
X107192Y-606228D01*
X107505Y-605493D01*
X107975Y-604863D01*
X108523Y-604443D01*
X109150Y-604338D01*
X109777Y-604443D01*
X110325Y-604863D01*
X110795Y-605493D01*
X111108Y-606228D01*
X111265Y-607068D01*
Y-607908D01*
X111108Y-608748D01*
X110795Y-609483D01*
X110325Y-610113D01*
X109777Y-610533D01*
X109150Y-610638D01*
G01X115450D02*
Y-607803D01*
X113883Y-604338D01*
G01X117017D02*
X115450Y-607803D01*
G01X120027Y-604338D02*
Y-608853D01*
X120340Y-609798D01*
X120967Y-610428D01*
X121750Y-610638D01*
X122533Y-610428D01*
X123160Y-609798D01*
X123473Y-608853D01*
Y-604338D01*
G01X126092Y-610638D02*
X128050Y-604338D01*
X130008Y-610638D01*
G01X129303Y-608433D02*
X126797D01*
G01X132548Y-610638D02*
Y-604338D01*
X136152Y-610638D01*
Y-604338D01*
G01X10073Y-614863D02*
X9603Y-614548D01*
X9055Y-614338D01*
X8428D01*
X7723Y-614653D01*
X7175Y-615178D01*
X6783Y-615808D01*
X6470Y-616858D01*
X6392Y-617803D01*
X6548Y-618748D01*
X6783Y-619378D01*
X7253Y-620008D01*
X7802Y-620428D01*
X8350Y-620638D01*
X8898D01*
X9447Y-620428D01*
X9917Y-620113D01*
X10308Y-619693D01*
G01X13710Y-614338D02*
X15590D01*
G01X14650D02*
Y-620638D01*
G01X13710D02*
X15590D01*
G01X20950Y-614338D02*
Y-620638D01*
G01X19148Y-614338D02*
X22752D01*
G01X27250Y-620638D02*
Y-617803D01*
X25683Y-614338D01*
G01X28817D02*
X27250Y-617803D01*
G01X38127Y-619378D02*
X38597Y-620113D01*
X39223Y-620533D01*
X39928Y-620638D01*
X40555Y-620533D01*
X41182Y-620008D01*
X41573Y-619378D01*
X41652Y-618748D01*
X41495Y-618013D01*
X40947Y-617488D01*
X40398Y-617278D01*
X39693D01*
G01X40398D02*
X40868Y-616963D01*
X41260Y-616438D01*
X41417Y-615808D01*
X41260Y-615178D01*
X40868Y-614653D01*
X40163Y-614338D01*
X39458Y-614443D01*
X38753Y-614863D01*
G01X44427Y-619378D02*
X44897Y-620113D01*
X45523Y-620533D01*
X46228Y-620638D01*
X46855Y-620533D01*
X47482Y-620008D01*
X47873Y-619378D01*
X47952Y-618748D01*
X47795Y-618013D01*
X47247Y-617488D01*
X46698Y-617278D01*
X45993D01*
G01X46698D02*
X47168Y-616963D01*
X47560Y-616438D01*
X47717Y-615808D01*
X47560Y-615178D01*
X47168Y-614653D01*
X46463Y-614338D01*
X45758Y-614443D01*
X45053Y-614863D01*
G01X50727Y-619378D02*
X51197Y-620113D01*
X51823Y-620533D01*
X52528Y-620638D01*
X53155Y-620533D01*
X53782Y-620008D01*
X54173Y-619378D01*
X54252Y-618748D01*
X54095Y-618013D01*
X53547Y-617488D01*
X52998Y-617278D01*
X52293D01*
G01X52998D02*
X53468Y-616963D01*
X53860Y-616438D01*
X54017Y-615808D01*
X53860Y-615178D01*
X53468Y-614653D01*
X52763Y-614338D01*
X52058Y-614443D01*
X51353Y-614863D01*
G01X58593Y-620638D02*
X58750Y-619273D01*
X58985Y-618118D01*
X59298Y-617068D01*
X59690Y-615913D01*
X60317Y-614338D01*
X57183D01*
G01X64893Y-620638D02*
X65050Y-619273D01*
X65285Y-618118D01*
X65598Y-617068D01*
X65990Y-615913D01*
X66617Y-614338D01*
X63483D01*
G01X71193Y-621793D02*
X71507Y-620428D01*
G01X77650Y-614338D02*
Y-620638D01*
G01X75848Y-614338D02*
X79452D01*
G01X81992Y-620638D02*
X83950Y-614338D01*
X85908Y-620638D01*
G01X85203Y-618433D02*
X82697D01*
G01X89310Y-614338D02*
X91190D01*
G01X90250D02*
Y-620638D01*
G01X89310D02*
X91190D01*
G01X94200Y-614338D02*
X95297Y-620638D01*
X96550Y-614338D01*
X97803Y-620638D01*
X98900Y-614338D01*
G01X100892Y-620638D02*
X102850Y-614338D01*
X104808Y-620638D01*
G01X104103Y-618433D02*
X101597D01*
G01X107348Y-620638D02*
Y-614338D01*
X110952Y-620638D01*
Y-614338D01*
G01X121358Y-622738D02*
X120575Y-621688D01*
X120183Y-620638D01*
Y-616438D01*
X120575Y-615388D01*
X121358Y-614338D01*
G01X132783Y-620638D02*
Y-614338D01*
X134742D01*
X135368Y-614653D01*
X135760Y-615073D01*
X135917Y-615913D01*
X135760Y-616753D01*
X135290Y-617278D01*
X134742Y-617593D01*
X132783D01*
G01X134742D02*
X135917Y-620638D01*
G01X140650Y-620848D02*
X140493Y-620743D01*
Y-620533D01*
X140650Y-620428D01*
X140807Y-620533D01*
Y-620743D01*
X140650Y-620848D01*
G01X146950Y-620638D02*
X146323Y-620533D01*
X145775Y-620113D01*
X145305Y-619483D01*
X144992Y-618748D01*
X144835Y-617908D01*
Y-617068D01*
X144992Y-616228D01*
X145305Y-615493D01*
X145775Y-614863D01*
X146323Y-614443D01*
X146950Y-614338D01*
X147577Y-614443D01*
X148125Y-614863D01*
X148595Y-615493D01*
X148908Y-616228D01*
X149065Y-617068D01*
Y-617908D01*
X148908Y-618748D01*
X148595Y-619483D01*
X148125Y-620113D01*
X147577Y-620533D01*
X146950Y-620638D01*
G01X153250Y-620848D02*
X153093Y-620743D01*
Y-620533D01*
X153250Y-620428D01*
X153407Y-620533D01*
Y-620743D01*
X153250Y-620848D01*
G01X161273Y-614863D02*
X160803Y-614548D01*
X160255Y-614338D01*
X159628D01*
X158923Y-614653D01*
X158375Y-615178D01*
X157983Y-615808D01*
X157670Y-616858D01*
X157592Y-617803D01*
X157748Y-618748D01*
X157983Y-619378D01*
X158453Y-620008D01*
X159002Y-620428D01*
X159550Y-620638D01*
X160098D01*
X160647Y-620428D01*
X161117Y-620113D01*
X161508Y-619693D01*
G01X165850Y-620848D02*
X165693Y-620743D01*
Y-620533D01*
X165850Y-620428D01*
X166007Y-620533D01*
Y-620743D01*
X165850Y-620848D01*
G01X172542Y-622738D02*
X173325Y-621688D01*
X173717Y-620638D01*
Y-616438D01*
X173325Y-615388D01*
X172542Y-614338D01*
G01X6548Y-600638D02*
Y-594338D01*
X10152Y-600638D01*
Y-594338D01*
G01X14650Y-600638D02*
X14023Y-600533D01*
X13475Y-600113D01*
X13005Y-599483D01*
X12692Y-598748D01*
X12535Y-597908D01*
Y-597068D01*
X12692Y-596228D01*
X13005Y-595493D01*
X13475Y-594863D01*
X14023Y-594443D01*
X14650Y-594338D01*
X15277Y-594443D01*
X15825Y-594863D01*
X16295Y-595493D01*
X16608Y-596228D01*
X16765Y-597068D01*
Y-597908D01*
X16608Y-598748D01*
X16295Y-599483D01*
X15825Y-600113D01*
X15277Y-600533D01*
X14650Y-600638D01*
G01X20950Y-600848D02*
X20793Y-600743D01*
Y-600533D01*
X20950Y-600428D01*
X21107Y-600533D01*
Y-600743D01*
X20950Y-600848D01*
G01X25762Y-595388D02*
X26232Y-594758D01*
X26780Y-594443D01*
X27407Y-594338D01*
X28190Y-594548D01*
X28738Y-595073D01*
X28895Y-595703D01*
X28817Y-596333D01*
X28503Y-596858D01*
X26937Y-597908D01*
X26232Y-598643D01*
X25762Y-599693D01*
X25605Y-600638D01*
X28895D01*
G01X33550D02*
Y-594338D01*
X32610Y-595598D01*
G01Y-600638D02*
X34490D01*
G01X39850D02*
Y-594338D01*
X38910Y-595598D01*
G01Y-600638D02*
X40790D01*
G01X45993Y-601793D02*
X46307Y-600428D01*
G01X50100Y-594338D02*
X51197Y-600638D01*
X52450Y-594338D01*
X53703Y-600638D01*
X54800Y-594338D01*
G01X60317Y-600638D02*
X57183D01*
Y-594338D01*
X60317D01*
G01X59063Y-597383D02*
X57183D01*
G01X63248Y-600638D02*
Y-594338D01*
X66852Y-600638D01*
Y-594338D01*
G01X69705Y-600638D02*
Y-594338D01*
G01X72995D02*
Y-600638D01*
G01Y-597488D02*
X69705D01*
G01X75927Y-594338D02*
Y-598853D01*
X76240Y-599798D01*
X76867Y-600428D01*
X77650Y-600638D01*
X78433Y-600428D01*
X79060Y-599798D01*
X79373Y-598853D01*
Y-594338D01*
G01X81992Y-600638D02*
X83950Y-594338D01*
X85908Y-600638D01*
G01X85203Y-598433D02*
X82697D01*
G01X95062Y-595388D02*
X95532Y-594758D01*
X96080Y-594443D01*
X96707Y-594338D01*
X97490Y-594548D01*
X98038Y-595073D01*
X98195Y-595703D01*
X98117Y-596333D01*
X97803Y-596858D01*
X96237Y-597908D01*
X95532Y-598643D01*
X95062Y-599693D01*
X94905Y-600638D01*
X98195D01*
G01X101048D02*
Y-594338D01*
X104652Y-600638D01*
Y-594338D01*
G01X107427Y-600638D02*
Y-594338D01*
X108993D01*
X109620Y-594653D01*
X110090Y-595073D01*
X110482Y-595703D01*
X110795Y-596438D01*
X110873Y-597488D01*
X110795Y-598538D01*
X110482Y-599273D01*
X110090Y-599903D01*
X109620Y-600323D01*
X108993Y-600638D01*
X107427D01*
G01X120183D02*
Y-594338D01*
X122142D01*
X122768Y-594653D01*
X123160Y-595073D01*
X123317Y-595913D01*
X123160Y-596753D01*
X122690Y-597278D01*
X122142Y-597593D01*
X120183D01*
G01X122142D02*
X123317Y-600638D01*
G01X126327D02*
Y-594338D01*
X127893D01*
X128520Y-594653D01*
X128990Y-595073D01*
X129382Y-595703D01*
X129695Y-596438D01*
X129773Y-597488D01*
X129695Y-598538D01*
X129382Y-599273D01*
X128990Y-599903D01*
X128520Y-600323D01*
X127893Y-600638D01*
X126327D01*
G01X134350Y-600848D02*
X134193Y-600743D01*
Y-600533D01*
X134350Y-600428D01*
X134507Y-600533D01*
Y-600743D01*
X134350Y-600848D01*
G01X30650Y-589938D02*
X28130Y-589521D01*
X25925Y-587855D01*
X24035Y-585355D01*
X22775Y-582438D01*
X22145Y-579105D01*
Y-575771D01*
X22775Y-572438D01*
X24035Y-569521D01*
X25925Y-567022D01*
X28130Y-565355D01*
X30650Y-564938D01*
X33170Y-565355D01*
X35375Y-567022D01*
X37265Y-569521D01*
X38525Y-572438D01*
X39155Y-575771D01*
Y-579105D01*
X38525Y-582438D01*
X37265Y-585355D01*
X35375Y-587855D01*
X33170Y-589521D01*
X30650Y-589938D01*
G01X33170Y-583271D02*
X36950Y-589938D01*
G01X50495Y-573272D02*
Y-584938D01*
X51755Y-587855D01*
X53645Y-589521D01*
X55850Y-589938D01*
X58055Y-589521D01*
X59945Y-587855D01*
X61205Y-584938D01*
G01Y-589938D02*
Y-573272D01*
G01X86720Y-589938D02*
Y-573272D01*
G01Y-576188D02*
X85460Y-574522D01*
X83570Y-573688D01*
X81365Y-573272D01*
X79160Y-574105D01*
X77270Y-575771D01*
X76010Y-578272D01*
X75380Y-581605D01*
X76010Y-584938D01*
X77270Y-587439D01*
X79160Y-589105D01*
X81365Y-589938D01*
X83570Y-589521D01*
X85460Y-588272D01*
X86720Y-586605D01*
G01X100895Y-589938D02*
Y-573272D01*
G01Y-577438D02*
X102155Y-575355D01*
X104045Y-573688D01*
X106565Y-573272D01*
X108770Y-573688D01*
X110660Y-575355D01*
X111605Y-578272D01*
Y-589938D01*
G01X131450Y-564938D02*
Y-589938D01*
G01X127040Y-573272D02*
X135860D01*
G01X162320Y-589938D02*
Y-573272D01*
G01Y-576188D02*
X161060Y-574522D01*
X159170Y-573688D01*
X156965Y-573272D01*
X154760Y-574105D01*
X152870Y-575771D01*
X151610Y-578272D01*
X150980Y-581605D01*
X151610Y-584938D01*
X152870Y-587439D01*
X154760Y-589105D01*
X156965Y-589938D01*
X159170Y-589521D01*
X161060Y-588272D01*
X162320Y-586605D01*
G01X215400Y-602638D02*
Y-594638D01*
X218000Y-601305D01*
X220600Y-594638D01*
Y-602638D01*
G01X223500D02*
X226000Y-594638D01*
X228500Y-602638D01*
G01X227600Y-599838D02*
X224400D01*
G01X231900Y-601572D02*
X232700Y-602238D01*
X233600Y-602638D01*
X234400D01*
X235200Y-602238D01*
X235800Y-601572D01*
X236100Y-600638D01*
X235900Y-599705D01*
X235400Y-598905D01*
X234500Y-598371D01*
X233300Y-598105D01*
X232600Y-597571D01*
X232300Y-596638D01*
X232500Y-595705D01*
X233000Y-595038D01*
X233700Y-594638D01*
X234400D01*
X235100Y-594905D01*
X235700Y-595571D01*
G01X239800Y-602638D02*
Y-594638D01*
G01X243600D02*
X239800Y-599572D01*
G01X244200Y-602638D02*
X241500Y-597305D01*
G01X248700Y-599971D02*
X251300D01*
G01X258800Y-598371D02*
X259200Y-597971D01*
X259500Y-597305D01*
X259700Y-596371D01*
X259500Y-595571D01*
X259100Y-595038D01*
X258400Y-594638D01*
X255700D01*
Y-602638D01*
X259000D01*
X259700Y-602105D01*
X260100Y-601305D01*
X260300Y-600371D01*
X260100Y-599438D01*
X259500Y-598638D01*
X258800Y-598371D01*
X255700D01*
G01X266000Y-602638D02*
X265200Y-602505D01*
X264500Y-601971D01*
X263900Y-601171D01*
X263500Y-600238D01*
X263300Y-599171D01*
Y-598105D01*
X263500Y-597038D01*
X263900Y-596105D01*
X264500Y-595305D01*
X265200Y-594771D01*
X266000Y-594638D01*
X266800Y-594771D01*
X267500Y-595305D01*
X268100Y-596105D01*
X268500Y-597038D01*
X268700Y-598105D01*
Y-599171D01*
X268500Y-600238D01*
X268100Y-601171D01*
X267500Y-601971D01*
X266800Y-602505D01*
X266000Y-602638D01*
G01X274000Y-594638D02*
Y-602638D01*
G01X271700Y-594638D02*
X276300D01*
G01X202000Y-569638D02*
Y-577638D01*
X206000D01*
G01X213800D02*
Y-572305D01*
G01Y-573238D02*
X213400Y-572705D01*
X212800Y-572438D01*
X212100Y-572305D01*
X211400Y-572571D01*
X210800Y-573105D01*
X210400Y-573905D01*
X210200Y-574971D01*
X210400Y-576038D01*
X210800Y-576838D01*
X211400Y-577371D01*
X212100Y-577638D01*
X212800Y-577505D01*
X213400Y-577105D01*
X213800Y-576572D01*
G01X217900Y-580038D02*
X218500Y-580305D01*
X219300Y-580038D01*
X219800Y-579505D01*
X220200Y-578838D01*
X220800Y-576705D01*
X222100Y-572305D01*
G01X218900D02*
X220800Y-576705D01*
G01X226500Y-574038D02*
X229700D01*
X229400Y-573105D01*
X228900Y-572571D01*
X228200Y-572305D01*
X227500Y-572438D01*
X226900Y-572838D01*
X226500Y-573771D01*
X226300Y-574572D01*
Y-575371D01*
X226500Y-576171D01*
X227000Y-576971D01*
X227600Y-577505D01*
X228300Y-577638D01*
X229000Y-577371D01*
X229700Y-576572D01*
G01X234600Y-577638D02*
Y-572305D01*
G01Y-573371D02*
X235100Y-572838D01*
X235600Y-572438D01*
X236300Y-572305D01*
X236800Y-572438D01*
X237400Y-572838D01*
G01X226000Y-626038D02*
X226500Y-626838D01*
X227100Y-627371D01*
X227800Y-627638D01*
X228600Y-627371D01*
X229200Y-626838D01*
X229800Y-626038D01*
X230000Y-624971D01*
Y-619638D01*
G01X237800Y-627638D02*
Y-622305D01*
G01Y-623238D02*
X237400Y-622705D01*
X236800Y-622438D01*
X236100Y-622305D01*
X235400Y-622571D01*
X234800Y-623105D01*
X234400Y-623905D01*
X234200Y-624971D01*
X234400Y-626038D01*
X234800Y-626838D01*
X235400Y-627371D01*
X236100Y-627638D01*
X236800Y-627505D01*
X237400Y-627105D01*
X237800Y-626572D01*
G01X245600Y-622971D02*
X244900Y-622438D01*
X244300Y-622305D01*
X243500Y-622571D01*
X242900Y-623105D01*
X242500Y-624038D01*
X242400Y-624971D01*
X242500Y-625905D01*
X242900Y-626705D01*
X243500Y-627371D01*
X244300Y-627638D01*
X245000Y-627371D01*
X245600Y-626838D01*
G01X250300Y-627638D02*
Y-619638D01*
G01X253500Y-622305D02*
X250300Y-625371D01*
G01X251600Y-624171D02*
X253700Y-627638D01*
G01X328600Y-620971D02*
X329200Y-620171D01*
X329900Y-619771D01*
X330700Y-619638D01*
X331700Y-619905D01*
X332400Y-620571D01*
X332600Y-621371D01*
X332500Y-622172D01*
X332100Y-622838D01*
X330100Y-624171D01*
X329200Y-625105D01*
X328600Y-626438D01*
X328400Y-627638D01*
X332600D01*
G01X338500Y-619638D02*
X337700Y-619905D01*
X337100Y-620571D01*
X336700Y-621371D01*
X336400Y-622438D01*
X336300Y-623638D01*
X336400Y-624838D01*
X336700Y-625905D01*
X337100Y-626705D01*
X337700Y-627371D01*
X338500Y-627638D01*
X339300Y-627371D01*
X339900Y-626705D01*
X340300Y-625905D01*
X340600Y-624838D01*
X340700Y-623638D01*
X340600Y-622438D01*
X340300Y-621371D01*
X339900Y-620571D01*
X339300Y-619905D01*
X338500Y-619638D01*
G01X344600Y-620971D02*
X345200Y-620171D01*
X345900Y-619771D01*
X346700Y-619638D01*
X347700Y-619905D01*
X348400Y-620571D01*
X348600Y-621371D01*
X348500Y-622172D01*
X348100Y-622838D01*
X346100Y-624171D01*
X345200Y-625105D01*
X344600Y-626438D01*
X344400Y-627638D01*
X348600D01*
G01X352300Y-626038D02*
X352900Y-626971D01*
X353700Y-627505D01*
X354600Y-627638D01*
X355400Y-627505D01*
X356200Y-626838D01*
X356700Y-626038D01*
X356800Y-625238D01*
X356600Y-624305D01*
X355900Y-623638D01*
X355200Y-623371D01*
X354300D01*
G01X355200D02*
X355800Y-622971D01*
X356300Y-622305D01*
X356500Y-621505D01*
X356300Y-620705D01*
X355800Y-620038D01*
X354900Y-619638D01*
X354000Y-619771D01*
X353100Y-620305D01*
G01X360700Y-627905D02*
X364300Y-619638D01*
G01X370500D02*
X369700Y-619905D01*
X369100Y-620571D01*
X368700Y-621371D01*
X368400Y-622438D01*
X368300Y-623638D01*
X368400Y-624838D01*
X368700Y-625905D01*
X369100Y-626705D01*
X369700Y-627371D01*
X370500Y-627638D01*
X371300Y-627371D01*
X371900Y-626705D01*
X372300Y-625905D01*
X372600Y-624838D01*
X372700Y-623638D01*
X372600Y-622438D01*
X372300Y-621371D01*
X371900Y-620571D01*
X371300Y-619905D01*
X370500Y-619638D01*
G01X379700Y-627638D02*
Y-619638D01*
X376000Y-625371D01*
X381000D01*
G01X384700Y-627905D02*
X388300Y-619638D01*
G01X394500Y-627638D02*
Y-619638D01*
X393300Y-621238D01*
G01Y-627638D02*
X395700D01*
G01X402300D02*
X402500Y-625905D01*
X402800Y-624438D01*
X403200Y-623105D01*
X403700Y-621638D01*
X404500Y-619638D01*
X400500D01*
G01X328300Y-602638D02*
Y-594638D01*
X330300D01*
X331100Y-595038D01*
X331700Y-595571D01*
X332200Y-596371D01*
X332600Y-597305D01*
X332700Y-598638D01*
X332600Y-599971D01*
X332200Y-600905D01*
X331700Y-601705D01*
X331100Y-602238D01*
X330300Y-602638D01*
X328300D01*
G01X336000D02*
X338500Y-594638D01*
X341000Y-602638D01*
G01X340100Y-599838D02*
X336900D01*
G01X344600Y-602638D02*
Y-594638D01*
X348400D01*
G01X347000Y-598505D02*
X344600D01*
G01X354500Y-594638D02*
X353700Y-594905D01*
X353100Y-595571D01*
X352700Y-596371D01*
X352400Y-597438D01*
X352300Y-598638D01*
X352400Y-599838D01*
X352700Y-600905D01*
X353100Y-601705D01*
X353700Y-602371D01*
X354500Y-602638D01*
X355300Y-602371D01*
X355900Y-601705D01*
X356300Y-600905D01*
X356600Y-599838D01*
X356700Y-598638D01*
X356600Y-597438D01*
X356300Y-596371D01*
X355900Y-595571D01*
X355300Y-594905D01*
X354500Y-594638D01*
G01X362500D02*
Y-602638D01*
G01X360200Y-594638D02*
X364800D01*
G01X367900Y-602638D02*
Y-594638D01*
X370500Y-601305D01*
X373100Y-594638D01*
Y-602638D01*
G01X379300Y-598371D02*
X379700Y-597971D01*
X380000Y-597305D01*
X380200Y-596371D01*
X380000Y-595571D01*
X379600Y-595038D01*
X378900Y-594638D01*
X376200D01*
Y-602638D01*
X379500D01*
X380200Y-602105D01*
X380600Y-601305D01*
X380800Y-600371D01*
X380600Y-599438D01*
X380000Y-598638D01*
X379300Y-598371D01*
X376200D01*
G01X384300Y-601038D02*
X384900Y-601971D01*
X385700Y-602505D01*
X386600Y-602638D01*
X387400Y-602505D01*
X388200Y-601838D01*
X388700Y-601038D01*
X388800Y-600238D01*
X388600Y-599305D01*
X387900Y-598638D01*
X387200Y-598371D01*
X386300D01*
G01X387200D02*
X387800Y-597971D01*
X388300Y-597305D01*
X388500Y-596505D01*
X388300Y-595705D01*
X387800Y-595038D01*
X386900Y-594638D01*
X386000Y-594771D01*
X385100Y-595305D01*
G01X393300Y-594638D02*
X395700D01*
G01X394500D02*
Y-602638D01*
G01X393300D02*
X395700D01*
G01X404700Y-595305D02*
X404100Y-594905D01*
X403400Y-594638D01*
X402600D01*
X401700Y-595038D01*
X401000Y-595705D01*
X400500Y-596505D01*
X400100Y-597838D01*
X400000Y-599038D01*
X400200Y-600238D01*
X400500Y-601038D01*
X401100Y-601838D01*
X401800Y-602371D01*
X402500Y-602638D01*
X403200D01*
X403900Y-602371D01*
X404500Y-601971D01*
X405000Y-601438D01*
G01X410500Y-594638D02*
X409700Y-594905D01*
X409100Y-595571D01*
X408700Y-596371D01*
X408400Y-597438D01*
X408300Y-598638D01*
X408400Y-599838D01*
X408700Y-600905D01*
X409100Y-601705D01*
X409700Y-602371D01*
X410500Y-602638D01*
X411300Y-602371D01*
X411900Y-601705D01*
X412300Y-600905D01*
X412600Y-599838D01*
X412700Y-598638D01*
X412600Y-597438D01*
X412300Y-596371D01*
X411900Y-595571D01*
X411300Y-594905D01*
X410500Y-594638D01*
G01X346100Y-577638D02*
Y-569638D01*
X349900D01*
G01X348500Y-573505D02*
X346100D01*
G01X356000Y-569638D02*
X355200Y-569905D01*
X354600Y-570571D01*
X354200Y-571371D01*
X353900Y-572438D01*
X353800Y-573638D01*
X353900Y-574838D01*
X354200Y-575905D01*
X354600Y-576705D01*
X355200Y-577371D01*
X356000Y-577638D01*
X356800Y-577371D01*
X357400Y-576705D01*
X357800Y-575905D01*
X358100Y-574838D01*
X358200Y-573638D01*
X358100Y-572438D01*
X357800Y-571371D01*
X357400Y-570571D01*
X356800Y-569905D01*
X356000Y-569638D01*
G01X364000D02*
Y-577638D01*
G01X361700Y-569638D02*
X366300D01*
G01X372600Y-573638D02*
X374600D01*
Y-576038D01*
X374000Y-576838D01*
X373300Y-577371D01*
X372300Y-577638D01*
X371300Y-577371D01*
X370600Y-576838D01*
X370000Y-576038D01*
X369600Y-575105D01*
X369400Y-574038D01*
Y-573105D01*
X369600Y-572305D01*
X370000Y-571371D01*
X370600Y-570571D01*
X371200Y-570038D01*
X372000Y-569638D01*
X372700D01*
X373500Y-569905D01*
X374100Y-570438D01*
G01X377000Y-580305D02*
X383000D01*
G01X385400Y-577638D02*
Y-569638D01*
X388000Y-576305D01*
X390600Y-569638D01*
Y-577638D01*
G01X396800Y-573371D02*
X397200Y-572971D01*
X397500Y-572305D01*
X397700Y-571371D01*
X397500Y-570571D01*
X397100Y-570038D01*
X396400Y-569638D01*
X393700D01*
Y-577638D01*
X397000D01*
X397700Y-577105D01*
X398100Y-576305D01*
X398300Y-575371D01*
X398100Y-574438D01*
X397500Y-573638D01*
X396800Y-573371D01*
X393700D01*
G01X417000Y-630638D02*
Y-622638D01*
X415800Y-624238D01*
G01Y-630638D02*
X418200D01*
G01X423100Y-627305D02*
X423800Y-626371D01*
X424400Y-625838D01*
X425200Y-625571D01*
X425900Y-625838D01*
X426400Y-626371D01*
X426800Y-627171D01*
X426900Y-628105D01*
X426800Y-628905D01*
X426400Y-629705D01*
X425800Y-630371D01*
X425100Y-630638D01*
X424300Y-630371D01*
X423600Y-629572D01*
X423200Y-628371D01*
X423100Y-627038D01*
X423300Y-625305D01*
X423600Y-624371D01*
X424100Y-623438D01*
X424800Y-622771D01*
X425500Y-622638D01*
X426200Y-622905D01*
X426700Y-623571D01*
G01X433000Y-630905D02*
X432800Y-630771D01*
Y-630505D01*
X433000Y-630371D01*
X433200Y-630505D01*
Y-630771D01*
X433000Y-630905D01*
G01X439100Y-627305D02*
X439800Y-626371D01*
X440400Y-625838D01*
X441200Y-625571D01*
X441900Y-625838D01*
X442400Y-626371D01*
X442800Y-627171D01*
X442900Y-628105D01*
X442800Y-628905D01*
X442400Y-629705D01*
X441800Y-630371D01*
X441100Y-630638D01*
X440300Y-630371D01*
X439600Y-629572D01*
X439200Y-628371D01*
X439100Y-627038D01*
X439300Y-625305D01*
X439600Y-624371D01*
X440100Y-623438D01*
X440800Y-622771D01*
X441500Y-622638D01*
X442200Y-622905D01*
X442700Y-623571D01*
G01X462000Y-630638D02*
Y-622638D01*
X460800Y-624238D01*
G01Y-630638D02*
X463200D01*
G01X469800D02*
X470000Y-628905D01*
X470300Y-627438D01*
X470700Y-626105D01*
X471200Y-624638D01*
X472000Y-622638D01*
X468000D01*
G01X478000Y-630905D02*
X477800Y-630771D01*
Y-630505D01*
X478000Y-630371D01*
X478200Y-630505D01*
Y-630771D01*
X478000Y-630905D01*
G01X484100Y-623971D02*
X484700Y-623171D01*
X485400Y-622771D01*
X486200Y-622638D01*
X487200Y-622905D01*
X487900Y-623571D01*
X488100Y-624371D01*
X488000Y-625172D01*
X487600Y-625838D01*
X485600Y-627171D01*
X484700Y-628105D01*
X484100Y-629438D01*
X483900Y-630638D01*
X488100D01*
G01X486200Y-598305D02*
X485600Y-597905D01*
X484900Y-597638D01*
X484100D01*
X483200Y-598038D01*
X482500Y-598705D01*
X482000Y-599505D01*
X481600Y-600838D01*
X481500Y-602038D01*
X481700Y-603238D01*
X482000Y-604038D01*
X482600Y-604838D01*
X483300Y-605371D01*
X484000Y-605638D01*
X484700D01*
X485400Y-605371D01*
X486000Y-604971D01*
X486500Y-604438D01*
G54D17*
X36500Y318017D03*
X40000D03*
X46102Y520392D03*
X51253Y1532086D03*
X55503Y755849D03*
X65159Y773921D03*
X66871Y1601307D03*
X53633Y1634913D03*
X58633D03*
X64438Y1658336D03*
X74169Y381709D03*
X92826Y1329572D03*
X86996Y1532086D03*
X103503Y1367731D03*
X98186Y1374054D03*
X103177Y1505895D03*
X124500Y1422017D03*
X136103Y1367731D03*
X130786Y1374054D03*
X130000Y1422017D03*
X168803Y1367731D03*
X163486Y1374054D03*
X183021Y1539229D03*
X182813Y1669013D03*
X182517Y1699248D03*
X201703Y1367731D03*
X196386Y1374054D03*
X207660Y1668695D03*
X203660Y1675695D03*
X207807Y1683812D03*
Y1698930D03*
X203807Y1690812D03*
X207807Y1705930D03*
X229186Y1374054D03*
X238063Y31270D03*
X233203Y749097D03*
X234503Y1367731D03*
X268971Y799705D03*
X268103Y1321585D03*
X262786Y1327908D03*
X282716Y42882D03*
X287671Y1521139D03*
X283671D03*
X297520Y15254D03*
X297315Y582971D03*
X295682Y1327880D03*
X300999Y1321557D03*
X311716Y42882D03*
X307716D03*
X311083Y1539229D03*
X328586Y1327823D03*
X333903Y1321500D03*
X362157Y543432D03*
Y550432D03*
X361386Y1328023D03*
X366703Y1321700D03*
X385443Y591820D03*
X389443D03*
X381443D03*
X393371Y966505D03*
X393968Y1347354D03*
X397657Y577432D03*
X399285Y1341031D03*
X408000Y1636017D03*
X422048Y114877D03*
X423921Y1006440D03*
X415733Y1521139D03*
X411733D03*
X433226Y111522D03*
X425548Y114877D03*
X429726Y111522D03*
X437710Y242682D03*
X438882Y1006440D03*
X435141D03*
X427661D03*
X431401D03*
X430691Y1303261D03*
X432000Y1643517D03*
X448890Y110524D03*
X452890D03*
X451710Y241682D03*
X441710Y242682D03*
X447710Y241682D03*
X446362Y1006440D03*
X450102D03*
X442622D03*
X453842D03*
X441159Y1051783D03*
X447194Y1539229D03*
X457582Y1006440D03*
X461186Y1635967D03*
X461000Y1644017D03*
X499576Y127915D03*
X487271Y966505D03*
X503576Y127915D03*
X514576Y128515D03*
X508670Y144562D03*
X504670D03*
X504618Y163665D03*
X508618D03*
X519091Y122224D03*
Y129224D03*
X523091D03*
X539120Y34079D03*
X535117Y34052D03*
X542723Y34093D03*
X534876Y124006D03*
X538876D03*
X544680Y137510D03*
X543026Y250630D03*
X553620Y34279D03*
X549919Y34179D03*
X548610Y51752D03*
X548680Y137510D03*
X547844Y1521139D03*
X551844D03*
X589444Y68178D03*
X579771Y800405D03*
X583671Y800505D03*
X575256Y1539229D03*
X594444Y68178D03*
X602334Y64860D03*
X595571Y793705D03*
X599471D03*
X601771Y1269790D03*
X616815Y64860D03*
X610315D03*
X606263D03*
X607671Y782905D03*
X611671D03*
X605771Y1269790D03*
X622007Y69265D03*
X632800Y751117D03*
X628800D03*
X643146Y34003D03*
X647258Y1700787D03*
Y1693787D03*
Y1714787D03*
X643258Y1707787D03*
X656286Y34003D03*
X662863Y55467D03*
X658735Y55456D03*
X651258Y1697637D03*
Y1711637D03*
X674963Y30259D03*
X670964D03*
X678291Y52199D03*
X670500Y384879D03*
X675500Y393379D03*
X680621Y30259D03*
X685838Y30237D03*
X692466Y38467D03*
X682291Y51339D03*
X686291Y52699D03*
X681500Y117017D03*
X683500Y393379D03*
X679500D03*
X691500D03*
X687560D03*
X683398Y1647167D03*
X697893Y38467D03*
X693954Y125044D03*
X707500Y393379D03*
X703500D03*
X695500D03*
X699500D03*
X707800Y522579D03*
X705742Y1392063D03*
X719950Y52062D03*
X714666Y91650D03*
X722666D03*
X718666D03*
X710666D03*
X714703Y380893D03*
X723500Y393379D03*
X721909Y525269D03*
X714845Y525441D03*
X711059Y1385740D03*
X721950Y1580875D03*
X721890Y1601754D03*
X709317Y1624303D03*
X713317Y1634803D03*
X717422Y1645854D03*
X713771Y1657482D03*
X715927Y1679221D03*
X721632Y1674400D03*
X737596Y52062D03*
X733643D03*
X724645D03*
X729294D03*
X735457Y380745D03*
X735500Y393379D03*
X731500D03*
X730152Y437361D03*
X736439Y497861D03*
X737610Y512171D03*
X738524Y1392163D03*
X727242Y1673586D03*
X749478Y52062D03*
X745475D03*
X741378D03*
X753036Y309762D03*
Y302762D03*
X747500Y380879D03*
X751500D03*
X743457Y380745D03*
X739457D03*
X743500Y393379D03*
X739652Y393361D03*
X751500Y393379D03*
X751972Y497973D03*
X744439Y497861D03*
X740439D03*
X748007Y498257D03*
X743841Y1385840D03*
X757038Y314277D03*
X755500Y393379D03*
X767500D03*
X760652Y497861D03*
X756652D03*
X764152D03*
X762350Y1581325D03*
X768500Y540379D03*
X781000Y566517D03*
X783974Y455895D03*
X785500Y529517D03*
X805450Y1584125D03*
X833445Y223235D03*
X847450Y1584125D03*
X862528Y264899D03*
X901000Y912517D03*
X889450Y1584125D03*
X917377Y881971D03*
X917000Y912517D03*
X916763Y986874D03*
X905487Y1138414D03*
X929603Y882438D03*
X925500Y910517D03*
X918000Y922017D03*
X929500Y920017D03*
X919500Y945017D03*
X946500Y910517D03*
X938500D03*
X942500Y920017D03*
X934500D03*
X932500Y945017D03*
X943798Y1663279D03*
X948000Y855517D03*
X949500Y873517D03*
X956500Y896517D03*
X961500D03*
X954500Y910517D03*
X950500Y920017D03*
X952512Y1138414D03*
X951798Y1655237D03*
X963500Y857517D03*
X967500Y1294517D03*
X1013306Y520663D03*
X1021911Y200145D03*
X1063968Y1329726D03*
X1075241Y1367712D03*
X1069924Y1374035D03*
X1107841Y1367712D03*
X1102524Y1374035D03*
X1122965Y1637320D03*
X1126000Y1675517D03*
X1140541Y1367712D03*
X1135224Y1374035D03*
X1129500Y1635517D03*
Y1675517D03*
X1147947Y1675922D03*
X1152000Y1676017D03*
X1168124Y1374035D03*
X1173441Y1367712D03*
X1190894Y1572229D03*
X1206241Y1367712D03*
X1200924Y1374035D03*
X1222094Y299658D03*
X1226094D03*
Y308658D03*
X1225934Y777399D03*
X1229934D03*
X1225500Y1408517D03*
X1244232Y1321566D03*
X1238915Y1327889D03*
X1231000Y1408517D03*
X1257177Y801341D03*
X1253177D03*
X1264177D03*
X1273177D03*
X1271811Y1327861D03*
X1277128Y1321538D03*
X1304715Y1327804D03*
X1291544Y1554139D03*
X1295544D03*
X1310032Y1321481D03*
X1318956Y1572229D03*
X1329477Y1215895D03*
X1348421Y1187144D03*
X1337977Y1215895D03*
X1337515Y1328004D03*
X1342832Y1321681D03*
X1352421Y1187144D03*
X1369677Y966505D03*
X1375414Y1341012D03*
X1370097Y1347335D03*
X1400063Y1006439D03*
X1403803D03*
X1407543D03*
X1405686Y1303275D03*
X1415024Y1006439D03*
X1422504D03*
X1411283D03*
X1418764D03*
X1417301Y1051782D03*
X1423606Y1554139D03*
X1419606D03*
X1426244Y1006439D03*
X1429984D03*
X1433724D03*
X1463177Y966505D03*
X1455068Y1572229D03*
X1469832Y537919D03*
X1475257Y540994D03*
X1481177Y806005D03*
X1474177Y819505D03*
X1498543Y582382D03*
X1494543D03*
X1493177Y806005D03*
X1485177D03*
X1486177Y819505D03*
X1490177D03*
X1510757Y567994D03*
X1502543Y582382D03*
X1504000Y806005D03*
X1502177Y819505D03*
X1535512Y1235448D03*
X1556111Y801204D03*
X1555718Y1554139D03*
X1559917Y801194D03*
X1565502Y1341701D03*
X1568906Y1356195D03*
X1559718Y1554139D03*
X1574000Y565517D03*
X1580924Y1348715D03*
X1581181Y1373390D03*
X1586000Y1373393D03*
X1578599Y1393949D03*
X1583411D03*
X1588099D03*
X1583130Y1572229D03*
X1595355Y797301D03*
X1590827Y1257371D03*
X1594827D03*
X1595438Y1373303D03*
X1590723Y1373383D03*
X1599657Y1373358D03*
X1592788Y1393949D03*
X1597674D03*
X1629826Y1421458D03*
X1658792Y1385029D03*
X1653475Y1391352D03*
X1691574Y1385129D03*
X1686257Y1391452D03*
X1689383Y1716685D03*
Y1723685D03*
X1693383Y1720535D03*
X1713173Y31261D03*
X1720462Y73622D03*
X1724462D03*
X1727429Y1672473D03*
X1731429D03*
X1741519Y1571602D03*
X1766062Y40120D03*
X1760929Y1651473D03*
X1769757Y31417D03*
X1774279Y1565122D03*
X1791645Y187914D03*
X1797994Y179536D03*
X1801979Y1530922D03*
G54D26*
X45608Y386993D03*
X45775Y393408D03*
X45861Y528304D03*
X45999Y533985D03*
X52292Y1589981D03*
Y1585981D03*
X38150Y1598896D03*
X45184Y1625405D03*
X50650Y1612696D03*
X62445Y443677D03*
X80876Y767766D03*
Y771366D03*
X79150Y1625396D03*
Y1620896D03*
Y1616396D03*
X87907Y960966D03*
X87017Y1417000D03*
Y1412500D03*
Y1408000D03*
X96017Y1412500D03*
X87017Y1426000D03*
Y1421500D03*
X96017D03*
Y1426000D03*
Y1430500D03*
X87017D03*
Y1440000D03*
X96017D03*
Y1435500D03*
X98176Y751766D03*
X110577Y767766D03*
X100577Y767266D03*
X110577Y771366D03*
X126676Y751766D03*
X117608Y960966D03*
X140409Y767400D03*
X130278Y767266D03*
X140409Y771200D03*
X130192Y1680513D03*
X156176Y751766D03*
X147308Y960966D03*
X170079Y767666D03*
X159917Y767266D03*
X170079Y771266D03*
X185676Y751766D03*
X177009Y960966D03*
X197676Y751266D03*
X199810Y767400D03*
X189679Y767266D03*
X199779Y771366D03*
X198198Y1652454D03*
Y1648454D03*
X206710Y960966D03*
X229150Y583948D03*
X219280Y767266D03*
X232380Y767766D03*
Y771366D03*
X248988Y772388D03*
Y776388D03*
X274788Y801888D03*
X282268Y804048D03*
X295658Y37420D03*
X345517Y578500D03*
Y582500D03*
X353674Y550415D03*
Y554415D03*
Y566415D03*
X362100Y590479D03*
X353674Y590415D03*
Y586415D03*
X358728Y1193918D03*
Y1187862D03*
X358788Y1202388D03*
X379788Y1207488D03*
X370448Y1199648D03*
X370408Y1211538D03*
X388288Y981766D03*
X386352Y978266D03*
X388788Y1000266D03*
Y987766D03*
X388688Y994488D03*
X394176Y1010766D03*
X388676Y1007266D03*
X386623Y1015474D03*
X394103D03*
X386676Y1010766D03*
X394103Y1019017D03*
X386623D03*
Y1022560D03*
X394103D03*
X382734Y1677874D03*
X397674Y557415D03*
Y561415D03*
Y565415D03*
Y569415D03*
X397788Y966488D03*
X403288Y981766D03*
X397652Y978266D03*
X395788Y981766D03*
X396288Y987766D03*
X395688Y994488D03*
X403788Y987766D03*
X395688Y1000266D03*
X401676Y1010766D03*
X407176Y1007266D03*
X401583Y1015474D03*
Y1019017D03*
X406676Y1028266D03*
X401583Y1022560D03*
X406676Y1034266D03*
X398788Y1071988D03*
X409993Y1610161D03*
X410020Y1615400D03*
X399517Y1626800D03*
X404523Y1631219D03*
X420288Y966488D03*
X420176Y978266D03*
X410788Y981766D03*
X418288D03*
X410788Y987766D03*
X417762Y987761D03*
X415683Y1006123D03*
X425133Y1014766D03*
X415683Y1009864D03*
Y1013604D03*
Y1021084D03*
Y1028564D03*
Y1017344D03*
X425115Y1023013D03*
X415683Y1024824D03*
X425115Y1018879D03*
X421176Y1060266D03*
X421288Y1071988D03*
X414017Y1657500D03*
X429818Y120209D03*
Y124209D03*
Y132297D03*
Y128297D03*
X425788Y981766D03*
X438676Y989766D03*
X438601Y997766D03*
Y993766D03*
X434958Y1014745D03*
X438601Y1001766D03*
X434958Y1023013D03*
Y1018879D03*
X437017Y1641500D03*
Y1646500D03*
X451788Y969988D03*
X454052Y1014745D03*
X443816D03*
Y1023013D03*
X454052D03*
Y1018879D03*
X443816D03*
X452788Y1068488D03*
X459549Y112039D03*
Y108039D03*
X464788Y966488D03*
X464176Y978266D03*
X465676Y1060266D03*
X465788Y1071988D03*
X478085Y281093D03*
X477176Y1060266D03*
X488515Y285893D03*
X487388Y1060288D03*
X511938Y124498D03*
X504443Y140498D03*
X505649Y157898D03*
Y153898D03*
X527108Y129207D03*
Y133207D03*
X544397Y144493D03*
Y148493D03*
Y160493D03*
Y164493D03*
Y156493D03*
Y152493D03*
X569078Y1234075D03*
X569098Y1238165D03*
X569874Y1252788D03*
X569118Y1245965D03*
Y1242105D03*
X561672Y1245927D03*
X573363Y1261913D03*
X588676Y1238075D03*
X581676Y1234075D03*
X602676Y1241575D03*
X619062Y55682D03*
X613288Y1266988D03*
X613298Y1278668D03*
X616733Y1379093D03*
X624112Y51682D03*
X622299Y65173D03*
X628150Y1368752D03*
X622137Y1388057D03*
X638239Y53747D03*
X638162Y70040D03*
Y66040D03*
X647956Y64745D03*
X647924Y68572D03*
X644361Y439518D03*
X643187Y461930D03*
X644434Y479141D03*
X645507Y751266D03*
X648846Y767266D03*
X655821Y444497D03*
X656517Y457862D03*
Y469862D03*
Y465862D03*
X659039Y767300D03*
Y771100D03*
X657484Y1641522D03*
X650484D03*
X654334Y1637522D03*
X666497Y210362D03*
Y206362D03*
Y202362D03*
X672515Y404646D03*
X672529Y413863D03*
X672538Y409222D03*
X672589Y422000D03*
X672542Y473362D03*
X675007Y751766D03*
X678547Y767266D03*
X677478Y1633042D03*
Y1637042D03*
X676914Y1650419D03*
X675589Y1684739D03*
X693569Y502534D03*
X688017Y497000D03*
X688740Y767300D03*
Y771100D03*
X689487Y1662341D03*
X689490Y1658331D03*
X682427Y1684760D03*
X704507Y751766D03*
X708248Y767266D03*
X702775Y1631036D03*
X718441Y767300D03*
Y771100D03*
X720267Y1590753D03*
X718209Y1628911D03*
Y1632961D03*
X729544Y582036D03*
X734007Y751766D03*
X737949Y767266D03*
X725608Y1643997D03*
X749180Y76029D03*
X739017Y564000D03*
X739220Y569245D03*
X739073Y573171D03*
X748141Y767300D03*
Y771100D03*
X767769Y499344D03*
X767650Y767266D03*
X775169Y423344D03*
Y463344D03*
Y479344D03*
Y475344D03*
Y471344D03*
X777869Y483344D03*
X775469Y491644D03*
X775169Y499344D03*
Y495344D03*
X777842Y767300D03*
Y771100D03*
X797908Y308062D03*
X790342Y456518D03*
Y460518D03*
X789669Y479344D03*
Y483344D03*
X786010Y487524D03*
X794412Y751765D03*
X797350Y767266D03*
X794392Y1345923D03*
X799037Y144262D03*
Y139262D03*
X807081Y276820D03*
X807135Y284311D03*
X806196Y504261D03*
X801263Y1345878D03*
X811231Y1486876D03*
Y1490876D03*
Y1496876D03*
Y1500876D03*
Y1506284D03*
Y1516284D03*
Y1510284D03*
Y1520284D03*
X823088Y288063D03*
X820361Y476159D03*
X855020Y273557D03*
X846999Y291559D03*
X849748Y301542D03*
X849907Y308852D03*
X849398Y1273971D03*
X849312Y1278139D03*
X849473Y1291468D03*
X849437Y1295981D03*
X902517Y853000D03*
X889724Y1145058D03*
X898100Y1268420D03*
X898144Y1272692D03*
X898019Y1281203D03*
X898067Y1276968D03*
X897810Y1298027D03*
X897771Y1293853D03*
X898043Y1289630D03*
X898065Y1285420D03*
X912517Y945000D03*
X928442Y197612D03*
X922871Y1266347D03*
X922947Y1283048D03*
X923099Y1278713D03*
X922972Y1274591D03*
X923021Y1270408D03*
X923103Y1295957D03*
X923026Y1291676D03*
X923048Y1287193D03*
X918517Y1302000D03*
Y1306000D03*
X935017Y850500D03*
X942017Y894500D03*
X936749Y1145058D03*
X954017Y903500D03*
X958017Y1283000D03*
Y1287000D03*
X954040Y1505777D03*
Y1509777D03*
X994386Y1267126D03*
X1005357Y1275768D03*
X1005436Y1279751D03*
X1005386Y1271743D03*
X1011244Y1290096D03*
X1043818Y751265D03*
X1046957Y767265D03*
X1057149Y767299D03*
Y771099D03*
X1064049Y960965D03*
X1074318Y751765D03*
X1076658Y767265D03*
X1086850Y767299D03*
Y771099D03*
X1093750Y960965D03*
X1102818Y751765D03*
X1106358Y767265D03*
X1116551Y767299D03*
Y771099D03*
X1123450Y960965D03*
X1115231Y1649513D03*
X1132318Y751765D03*
X1136059Y767265D03*
X1140613Y1673937D03*
X1133517Y1679000D03*
X1146252Y767299D03*
Y771099D03*
X1153151Y960965D03*
X1161818Y751765D03*
X1165760Y767265D03*
X1173818Y751265D03*
X1175952Y767299D03*
Y771099D03*
X1182852Y960965D03*
X1195461Y767265D03*
X1188017Y1396500D03*
Y1401000D03*
X1197017D03*
X1188017Y1414500D03*
Y1405500D03*
Y1410000D03*
X1197017D03*
Y1414500D03*
Y1419000D03*
Y1424000D03*
X1208522Y767665D03*
Y771465D03*
X1293492Y134409D03*
X1304183Y537303D03*
X1333694Y1207988D03*
Y1211488D03*
X1362494Y978265D03*
X1362818Y1010765D03*
X1362765Y1015473D03*
Y1022559D03*
Y1019016D03*
X1363694Y1060265D03*
X1352694Y1207988D03*
X1374194Y966488D03*
X1373794Y978265D03*
X1364694Y981765D03*
X1372194D03*
X1364694Y1000265D03*
X1372094D03*
X1364694Y987765D03*
X1371694Y994265D03*
X1364694D03*
X1372194Y987765D03*
X1370245Y1015473D03*
X1377725D03*
X1370318Y1010765D03*
X1377818D03*
X1364818Y1007265D03*
X1377725Y1019016D03*
X1370245D03*
Y1022559D03*
X1377725D03*
X1366194Y1056765D03*
X1375194Y1071988D03*
X1379694Y981765D03*
X1387194D03*
X1393894Y987765D03*
X1386694D03*
X1379694D03*
X1391825Y1013603D03*
X1383318Y1007265D03*
X1391825Y1006122D03*
Y1009863D03*
Y1017343D03*
Y1021083D03*
Y1024823D03*
X1382818Y1028265D03*
X1391825Y1028563D03*
X1382818Y1034265D03*
X1396194Y966488D03*
X1394694Y981765D03*
X1401694D03*
X1396318Y978265D03*
X1401257Y1014744D03*
Y1018878D03*
Y1023012D03*
X1397318Y1060265D03*
X1397194Y1071988D03*
X1408115Y1641405D03*
X1406906Y1649720D03*
X1414743Y993765D03*
X1414818Y989765D03*
X1414743Y997765D03*
X1411100Y1014744D03*
X1419958D03*
X1414743Y1001765D03*
X1419958Y1018878D03*
X1411100Y1023012D03*
Y1018878D03*
X1419958Y1023012D03*
X1415186Y1641431D03*
X1414028Y1649716D03*
X1427694Y969988D03*
X1430194Y1014744D03*
Y1023012D03*
Y1018878D03*
X1428994Y1068488D03*
X1446044Y531318D03*
X1445544Y561318D03*
X1443804Y847652D03*
X1449820Y843652D03*
X1440694Y966488D03*
X1440318Y978265D03*
X1441818Y1060265D03*
X1441694Y1071988D03*
X1466774Y544977D03*
Y556977D03*
Y580977D03*
Y576977D03*
Y568977D03*
Y572977D03*
X1463618Y1060265D03*
X1476200Y581658D03*
X1510774Y547977D03*
Y551977D03*
Y555977D03*
Y559977D03*
X1528194Y797688D03*
Y801488D03*
X1558194Y1234162D03*
X1564780Y1237662D03*
X1559724Y1290418D03*
Y1293918D03*
X1567194Y1286108D03*
X1576320Y1235366D03*
X1583320Y1239866D03*
X1582464Y1264488D03*
Y1260588D03*
X1599694Y1282988D03*
Y1290988D03*
Y1298988D03*
Y1294988D03*
X1606063Y1307553D03*
X1621318Y752765D03*
X1624988Y767265D03*
X1635180D03*
Y771065D03*
X1650818Y753265D03*
X1654689Y767265D03*
X1664881D03*
Y771065D03*
X1687442Y118762D03*
X1677792Y131762D03*
X1687442D03*
Y126762D03*
Y122762D03*
X1677792Y136762D03*
X1687442Y141762D03*
Y136762D03*
Y149762D03*
Y145762D03*
Y157762D03*
Y166762D03*
X1681818Y753265D03*
X1684390Y767265D03*
X1694582D03*
Y771065D03*
X1713280Y43654D03*
Y39654D03*
Y51654D03*
Y47654D03*
X1710318Y752765D03*
X1714091Y767265D03*
X1724283Y767299D03*
Y771099D03*
X1726946Y1654456D03*
Y1681456D03*
X1739818Y752765D03*
X1743792Y767265D03*
X1753983Y767305D03*
Y771105D03*
X1769818Y753265D03*
X1773492Y767265D03*
X1769382Y1669037D03*
X1767980Y1661465D03*
X1768180Y1672965D03*
X1783684Y767565D03*
Y771365D03*
X1811139Y170869D03*
G54D119*
X1462113Y1668854D03*
Y1663854D03*
Y1678854D03*
Y1673854D03*
X1482585Y1663854D03*
Y1668854D03*
Y1673854D03*
Y1678854D03*
G54D44*
X250326Y185236D03*
X368437D03*
G54D71*
X591132Y1244425D03*
X582786Y1250725D03*
Y1244425D03*
X591132Y1250725D03*
X1560130Y1249812D03*
Y1243512D03*
X1568476D03*
Y1249812D03*
G54D62*
X417441Y1639260D03*
X420000D03*
X422559D03*
Y1646740D03*
X420000D03*
X417441D03*
X427441Y1637740D03*
X430000D03*
X427441Y1630260D03*
X432559D03*
X430000D03*
X432559Y1637740D03*
X657392Y1625582D03*
X654833D03*
X652274D03*
X657392Y1633062D03*
X652274D03*
X654833D03*
G54D53*
X367996Y558596D03*
X369570D03*
X371145D03*
X372720D03*
X374295D03*
X375870D03*
X377444D03*
X379019D03*
Y581234D03*
X377444D03*
X375870D03*
X374295D03*
X372720D03*
X371145D03*
X369570D03*
X367996D03*
X380594Y558596D03*
X382169D03*
X383744D03*
X385318D03*
Y581234D03*
X383744D03*
X382169D03*
X380594D03*
X1481096Y549158D03*
X1482670D03*
Y571796D03*
X1481096D03*
X1484245Y549158D03*
X1485820D03*
X1487395D03*
X1488970D03*
X1490544D03*
X1492119D03*
X1493694D03*
X1495269D03*
X1496844D03*
Y571796D03*
X1495269D03*
X1493694D03*
X1492119D03*
X1490544D03*
X1488970D03*
X1487395D03*
X1485820D03*
X1484245D03*
X1498418Y549158D03*
Y571796D03*
G54D35*
X99729Y289822D03*
Y310256D03*
X757184Y1722772D03*
X1072863Y1429176D03*
X1080970Y1660958D03*
X1299439Y92812D03*
X1550377Y581353D03*
G54D80*
X676509Y145866D03*
X1859986Y1403418D03*
X1859706Y1709011D03*
X1866790Y463389D03*
X1871790Y476573D03*
X1861790D03*
X1870648Y783729D03*
X1860648D03*
X1865648Y796913D03*
X1867295Y837583D03*
X1862295Y850767D03*
X1872295D03*
X1871790Y1158071D03*
X1861790D03*
X1866790Y1171255D03*
X1864986Y1390234D03*
X1869986Y1403418D03*
X1869706Y1709011D03*
X1864706Y1722195D03*
X1886862Y94107D03*
X1881862Y107291D03*
X1882340Y410829D03*
X1887340Y424013D03*
X1887711Y463680D03*
X1882711Y476864D03*
X1882240Y783474D03*
X1887240Y796658D03*
X1888273Y837632D03*
X1883273Y850816D03*
X1882579Y1158348D03*
X1887579Y1171532D03*
X1886223Y1391283D03*
X1881223Y1404467D03*
X1881177Y1709323D03*
X1886177Y1722507D03*
X1891862Y107291D03*
X1892340Y410829D03*
X1892711Y476864D03*
X1892240Y783474D03*
X1893273Y850816D03*
X1892579Y1158348D03*
X1891223Y1404467D03*
X1891177Y1709323D03*
X2077012Y95128D03*
X2082012Y108312D03*
X2072012D03*
X2071128Y410829D03*
X2081128D03*
X2076128Y424013D03*
G54D63*
X434401Y971551D03*
X1410543Y971550D03*
G54D54*
X376657Y569915D03*
X1489757Y560477D03*
G54D72*
X599238Y1254075D03*
X609080D03*
X1586224Y1247707D03*
X1576382D03*
G54D36*
X117933Y605376D03*
X763602Y605413D03*
X1094076Y605378D03*
X1739745Y605411D03*
G54D27*
X50696Y439840D03*
Y441415D03*
Y442989D03*
Y444564D03*
X44396D03*
Y442989D03*
Y441415D03*
Y439840D03*
G54D18*
X33000Y318016D03*
X43500D03*
X38733Y1610612D03*
X48167Y1629921D03*
X65397Y381644D03*
X57544Y397012D03*
X53738Y396986D03*
X56722Y435542D03*
X60761Y435475D03*
X60822Y521311D03*
X53742Y531781D03*
X60772Y531931D03*
X59503Y755848D03*
X69998Y381753D03*
X81667Y1608921D03*
X77667D03*
X99000Y1444016D03*
X186579Y1536154D03*
X182813Y1662012D03*
X182517Y1692079D03*
X196029Y1536154D03*
X200753D03*
X191304D03*
X210202D03*
X214926D03*
X205478D03*
X203660Y1668694D03*
X203807Y1683811D03*
X207660Y1675694D03*
X203807Y1698929D03*
X207807Y1690811D03*
X203807Y1705929D03*
X219651Y1536154D03*
X224375D03*
X229100D03*
X242220Y33878D03*
X246220D03*
X241787Y59856D03*
X234827Y696589D03*
X238548Y1536154D03*
X243273D03*
X254122Y33886D03*
X250220Y33878D03*
X246805Y59856D03*
X252722Y1536154D03*
X257446D03*
X247997D03*
X272870Y653096D03*
X267553Y659419D03*
X269871Y792004D03*
X262777Y1536154D03*
X290716Y42881D03*
X286716D03*
X293520Y15253D03*
X303720Y42878D03*
X300020D03*
X305600Y687337D03*
X300283Y693660D03*
X314641Y1536154D03*
X319366D03*
X333053Y713810D03*
X324091Y1536154D03*
X328815D03*
X333540D03*
X338370Y707487D03*
X342988Y1536154D03*
X338264D03*
X347713D03*
X362073Y594487D03*
X363313Y806191D03*
X359813D03*
X356313D03*
X352813D03*
X363313Y814991D03*
X359813Y815091D03*
X356313D03*
X352813D03*
X361271Y1213504D03*
X357271D03*
X352437Y1536154D03*
X357162D03*
X371430Y707219D03*
X366113Y713542D03*
X366813Y806191D03*
X377313D03*
X373813D03*
X370313D03*
X366610Y1536154D03*
X371335D03*
X376059D03*
X395657Y549431D03*
X387657D03*
X391657D03*
X394271Y1069004D03*
X385508Y1536154D03*
X380784D03*
X390839D03*
X399657Y549431D03*
X403657D03*
X404470Y707287D03*
X399153Y713610D03*
X408500Y1646516D03*
X424874Y104628D03*
X420874D03*
X420748Y121876D03*
X423926Y1029020D03*
X420831Y1620675D03*
X416123Y1620696D03*
X411636Y1623840D03*
X412000Y1636016D03*
X432874Y104628D03*
X428874D03*
X436874D03*
X434990Y136658D03*
X431090D03*
X427190D03*
X438890D03*
X433710Y242681D03*
X437470Y689487D03*
X432153Y695810D03*
X440159Y967282D03*
Y974782D03*
Y982282D03*
X427666Y1029020D03*
X438886D03*
X431406D03*
X435146D03*
X428000Y1643516D03*
X440874Y104628D03*
X442790Y136658D03*
X442626Y1029020D03*
X450107D03*
X453847D03*
X446366D03*
X450752Y1536154D03*
X459457Y100980D03*
X455457D03*
X469870Y664887D03*
X464553Y671210D03*
X457587Y1029020D03*
X460202Y1536154D03*
X464926D03*
X469651D03*
X455477D03*
X457151Y1635958D03*
X457000Y1644016D03*
X476639Y312443D03*
X479099Y1536154D03*
X474375D03*
X483824D03*
X495652Y151561D03*
X499652D03*
X497153Y644710D03*
X488071Y1068804D03*
X488548Y1536154D03*
X493273D03*
X513618Y159964D03*
X502470Y638387D03*
X502721Y1536154D03*
X507446D03*
X512170D03*
X517618Y159964D03*
X525618D03*
X521618D03*
X518075Y837898D03*
X516895Y1536154D03*
X521619D03*
X526950D03*
X538968Y250651D03*
X535770Y604287D03*
X530453Y610610D03*
X544651Y647954D03*
X546350Y34101D03*
X548380Y130509D03*
X558968Y250651D03*
X564200Y52698D03*
X572200D03*
X568200Y52709D03*
X560200Y52704D03*
X567333Y66678D03*
X572171Y800404D03*
X576200Y52738D03*
X588968Y250651D03*
X587571Y800504D03*
X575671Y800404D03*
X578814Y1536154D03*
X588264D03*
X583539D03*
X602350Y52698D03*
X594405D03*
X590097D03*
X603771Y782904D03*
X591571Y793704D03*
X603261Y797456D03*
X602201Y1234591D03*
X597971Y1244004D03*
X602437Y1536154D03*
X592988D03*
X597713D03*
X614845Y52698D03*
X610285D03*
X606330D03*
X615571Y782904D03*
X606201Y1234591D03*
X612171Y1242804D03*
X607161Y1536154D03*
X616610D03*
X611886D03*
X627496Y77477D03*
X630783Y1536154D03*
X621335D03*
X647672Y34002D03*
X634220Y58981D03*
X645222Y52276D03*
X640670Y77477D03*
X646719Y427953D03*
X644957Y1536154D03*
X635508D03*
X640232D03*
X643258Y1700786D03*
Y1693786D03*
Y1714786D03*
X647258Y1707786D03*
X651910Y34002D03*
X649222Y52276D03*
X659045Y414877D03*
X658603Y1367020D03*
X649681Y1536154D03*
X655012D03*
X675500Y384878D03*
X668058Y1714468D03*
X690291Y54848D03*
X683500Y384878D03*
X679500D03*
X702481Y52674D03*
X698597Y52698D03*
X694400D03*
X707849Y127209D03*
X708652Y497860D03*
X700652D03*
X704652D03*
X705815Y1657472D03*
X709303Y53227D03*
X720010Y78745D03*
X716033D03*
X712043D03*
X719438Y380850D03*
X715500Y393378D03*
X711500D03*
X719500D03*
X708800Y418636D03*
X712652Y497860D03*
X720652D03*
X711344Y522348D03*
X718381Y525457D03*
X718500Y571516D03*
X714090Y1600559D03*
X717694Y1601744D03*
X713317Y1624302D03*
X709317Y1634802D03*
X709771Y1657481D03*
X717749Y1657475D03*
X722630Y1663914D03*
X724000Y78745D03*
X727500Y393378D03*
X724652Y497860D03*
X733160Y522957D03*
X733191Y516455D03*
X729624Y524410D03*
X725424Y525254D03*
X726302Y1660754D03*
X730302D03*
X747500Y393378D03*
X742956Y536540D03*
X748482Y551526D03*
X753010Y1576114D03*
Y1584114D03*
X763500Y380878D03*
X767500D03*
X759500Y393378D03*
X763500D03*
X760517Y551400D03*
X785500Y536516D03*
X791500Y541516D03*
X785000Y566516D03*
X789000D03*
X808220Y140078D03*
X821120Y139478D03*
X837500Y223168D03*
X841720Y212878D03*
X858528Y264898D03*
X899707Y1136574D03*
X915500Y857016D03*
X905500D03*
X910500D03*
X903843Y896718D03*
X909000Y912516D03*
X913000D03*
X905000D03*
X925500Y920016D03*
X918780Y1663278D03*
X931798D03*
X923798D03*
X927798D03*
X934000Y861016D03*
X943000Y855516D03*
X938000D03*
X946500Y920016D03*
X938500D03*
X946732Y1136574D03*
X939798Y1663278D03*
X935798D03*
X949500Y880516D03*
X954500Y920016D03*
X948500Y931016D03*
X961023Y1506139D03*
X947798Y1663278D03*
X951798D03*
X984555Y177499D03*
X1016567Y207644D03*
X1123228Y1653439D03*
X1118402Y1653994D03*
X1134649Y1653561D03*
X1194452Y1569154D03*
X1199177D03*
X1214094Y261149D03*
X1203902Y1569154D03*
X1208626D03*
X1213351D03*
X1230094Y261149D03*
X1222094D03*
Y308657D03*
X1222799Y1569154D03*
X1218075D03*
X1227524D03*
X1238094Y261149D03*
X1240177Y793504D03*
X1235177D03*
X1232248Y1569154D03*
X1236973D03*
X1254094Y261149D03*
X1246094D03*
X1247785Y300248D03*
X1251146Y1569154D03*
X1246421D03*
X1255870D03*
X1262094Y261149D03*
X1270094D03*
X1269177Y801340D03*
X1260677D03*
X1260595Y1569154D03*
X1265319D03*
X1270650D03*
X1286094Y261149D03*
X1278094D03*
X1282677Y794240D03*
X1286677D03*
X1282677Y801340D03*
X1294094Y261149D03*
X1302094D03*
X1318094D03*
X1310094D03*
X1307824Y593527D03*
X1326094Y261149D03*
X1334094D03*
X1332877Y844504D03*
X1333977Y1215894D03*
X1322514Y1569154D03*
X1331964D03*
X1327239D03*
X1342094Y261149D03*
X1346717Y666404D03*
X1336877Y844504D03*
X1346137Y1569154D03*
X1336688D03*
X1341413D03*
X1358094Y261149D03*
X1350094D03*
X1350861Y1569154D03*
X1360310D03*
X1355586D03*
X1366094Y261149D03*
X1378105Y628753D03*
X1370477Y1068904D03*
X1374483Y1569154D03*
X1379208D03*
X1365035D03*
X1383422Y622430D03*
X1393381Y1569154D03*
X1388657D03*
X1383932D03*
X1400068Y1029019D03*
X1403808D03*
X1407548D03*
X1398712Y1569154D03*
X1396901Y1654524D03*
X1416122Y655330D03*
X1410805Y661653D03*
X1416301Y967281D03*
Y974781D03*
Y982281D03*
X1422508Y1029019D03*
X1418768D03*
X1411288D03*
X1415028D03*
X1433729D03*
X1426249D03*
X1429989D03*
X1448722Y687910D03*
X1443405Y694233D03*
X1465832Y537918D03*
X1461159Y843098D03*
X1465559D03*
X1464177Y1068804D03*
X1468076Y1569154D03*
X1458626D03*
X1463351D03*
X1475473Y585349D03*
X1481640Y707487D03*
X1476323Y713810D03*
X1477177Y806004D03*
X1473177D03*
X1478177Y819504D03*
X1482177D03*
X1483159Y843098D03*
X1478759D03*
X1474359D03*
X1469959D03*
X1482249Y1569154D03*
X1472800D03*
X1477525D03*
X1489177Y806004D03*
X1498177Y819504D03*
X1494177D03*
X1487559Y843098D03*
X1491959D03*
X1496359D03*
X1486973Y1569154D03*
X1491698D03*
X1496422D03*
X1508757Y539993D03*
X1500757D03*
X1504757D03*
X1512757D03*
X1509405Y713810D03*
X1500759Y843098D03*
X1510595Y1569154D03*
X1501147D03*
X1516757Y539993D03*
X1514722Y707487D03*
X1515320Y1569154D03*
X1524769D03*
X1520044D03*
X1542205Y713810D03*
X1539782Y1235447D03*
X1529493Y1569154D03*
X1534824D03*
X1547522Y707487D03*
X1555603Y788924D03*
X1550432Y788842D03*
X1543772Y1235417D03*
X1567836Y570963D03*
X1559618Y788890D03*
X1569148Y1341714D03*
X1572924D03*
X1572906Y1356194D03*
X1580652Y685547D03*
X1575335Y691870D03*
X1579205Y1303085D03*
X1580924Y1341714D03*
Y1356194D03*
X1586688Y1569154D03*
X1592852Y1301074D03*
X1596138Y1569154D03*
X1600862D03*
X1591413D03*
X1609141Y595422D03*
X1613422Y651778D03*
X1608105Y658101D03*
X1608652Y1289329D03*
Y1297679D03*
X1610311Y1569154D03*
X1615035D03*
X1605587D03*
X1620379Y547451D03*
X1624484Y1569154D03*
X1619760D03*
X1629209D03*
X1646422Y632778D03*
X1641105Y639101D03*
X1643382Y1569154D03*
X1638657D03*
X1655147Y676824D03*
X1657555Y1569154D03*
X1652831D03*
X1648106D03*
X1662886D03*
X1690560Y427128D03*
X1680147Y1308074D03*
X1685383Y1716684D03*
Y1723684D03*
X1712799Y104368D03*
X1710230Y1723366D03*
X1750463Y1646481D03*
X1762062Y40119D03*
X1755463Y1646481D03*
X1773757Y31416D03*
X1777754Y40385D03*
X1773554Y40225D03*
X1769900D03*
X1781990Y40271D03*
X1787672Y50102D03*
X1791672D03*
X1807296Y257549D03*
G54D45*
X238779Y1643661D03*
X246653Y1649173D03*
Y1653897D03*
X238779Y1667283D03*
Y1672007D03*
X246653Y1734212D03*
X254527Y1643661D03*
Y1653110D03*
Y1657834D03*
X270275Y1643661D03*
X262401Y1649173D03*
Y1653897D03*
Y1663346D03*
Y1668070D03*
Y1734212D03*
X286023Y1643661D03*
X278149Y1734212D03*
X305709Y1672007D03*
X321457D03*
X313583Y1734212D03*
X329331D03*
X337205Y1672007D03*
X345079Y1734212D03*
X352953Y1672007D03*
X502952D03*
X510826Y1734212D03*
X518700Y1672007D03*
X526574Y1734212D03*
X534448Y1672007D03*
X542322Y1734212D03*
X550196Y1672007D03*
X569882D03*
X585630D03*
X577756Y1734212D03*
X601378Y1672007D03*
X593504Y1734212D03*
X617126Y1672007D03*
X609252Y1734212D03*
X1246652Y1672007D03*
X1254526Y1734212D03*
X1262400Y1672007D03*
X1270274Y1734212D03*
X1278148Y1672007D03*
X1286022Y1734212D03*
X1293896Y1672007D03*
X1313582D03*
X1329330D03*
X1321456Y1734212D03*
X1345078Y1672007D03*
X1337204Y1734212D03*
X1360826Y1672007D03*
X1352952Y1734212D03*
X1510826Y1672007D03*
X1526574D03*
X1518700Y1734212D03*
X1542322Y1672007D03*
X1534448Y1734212D03*
X1558070Y1672007D03*
X1550196Y1734212D03*
X1577756Y1672007D03*
X1585630Y1734212D03*
X1593504Y1672007D03*
X1601378Y1734212D03*
X1609252Y1672007D03*
X1617126Y1734212D03*
X1625000Y1672007D03*
G54D81*
X676509Y224606D03*
G54D90*
X731743Y-13871D03*
X1183222Y-30011D03*
Y-10011D03*
Y9989D03*
X1442081Y-30011D03*
Y-10011D03*
Y9989D03*
X1735375Y-34212D03*
G54D64*
X432917Y968982D03*
X1409059Y968981D03*
G54D46*
X277098Y185236D03*
X395208D03*
X887519Y1528191D03*
G54D55*
X385023Y-13871D03*
X836502Y-30011D03*
Y-10011D03*
Y9989D03*
X1240022Y-30011D03*
Y-10011D03*
Y9989D03*
X1533316Y-34212D03*
G54D37*
X169288Y1506640D03*
X171388D03*
X169288Y1516140D03*
X171388D03*
X169288Y1522540D03*
X171388D03*
X169288Y1512940D03*
X171388D03*
X169288Y1519340D03*
X171388D03*
X169288Y1509840D03*
X171388D03*
X177763Y1523820D03*
X179863D03*
X172765Y1625407D03*
X174865D03*
X172765Y1628707D03*
X174865D03*
X202631Y1638154D03*
X204731D03*
X202631Y1641454D03*
X204731D03*
X274750Y1507400D03*
X266473Y1526648D03*
X264373D03*
X276850Y1507400D03*
X297350Y1510800D03*
X299450D03*
X292350D03*
X294450D03*
X297350Y1518040D03*
X299450D03*
X292350D03*
X294450D03*
X297350Y1514420D03*
X299450D03*
X292350D03*
X294450D03*
X305825Y1523820D03*
X307925D03*
X394535Y1526648D03*
X392435D03*
X402812Y1507400D03*
X404912D03*
X433461Y1510800D03*
X435561D03*
X428461D03*
X430561D03*
X433461Y1518040D03*
X435561D03*
X428461D03*
X430561D03*
X433461Y1514420D03*
X435561D03*
X428461D03*
X430561D03*
X441936Y1523820D03*
X444036D03*
X441947Y1528728D03*
X444047D03*
X528546Y1526648D03*
X538923Y1507400D03*
X541023D03*
X530646Y1526648D03*
X556523Y1510800D03*
X558623D03*
X556523Y1518040D03*
X558623D03*
X556523Y1514420D03*
X558623D03*
X561523Y1510800D03*
X563623D03*
X561523Y1518040D03*
X563623D03*
X561523Y1514420D03*
X563623D03*
X569998Y1523820D03*
X572098D03*
X617950Y1641600D03*
Y1638400D03*
X620050Y1641600D03*
Y1638400D03*
X628602Y1635949D03*
X630702D03*
X644448Y1642896D03*
X642348D03*
X638610Y1650639D03*
X636510D03*
X663453Y1509072D03*
X665553D03*
X841950Y1315000D03*
Y1319000D03*
Y1333000D03*
Y1337000D03*
X853950Y1306000D03*
X856050D03*
X853950Y1310000D03*
X856050D03*
X847050D03*
X844950D03*
X847050Y1306000D03*
X844950D03*
X847050Y1302000D03*
X844950D03*
X853950D03*
X856050D03*
X844050Y1315000D03*
Y1319000D03*
X855950D03*
Y1315000D03*
X847750Y1324000D03*
X845650D03*
X847750Y1328000D03*
X845650D03*
X855950Y1337000D03*
Y1333000D03*
X847750Y1342000D03*
X845650D03*
X844050Y1333000D03*
Y1337000D03*
X847750Y1346000D03*
X845650D03*
X858050Y1319000D03*
Y1315000D03*
X857450Y1324000D03*
X859550D03*
X857450Y1328000D03*
X859550D03*
X858050Y1337000D03*
Y1333000D03*
X857450Y1342000D03*
X859550D03*
X857450Y1346000D03*
X859550D03*
X887450Y1307500D03*
X889550D03*
X907950Y1302000D03*
X910050D03*
X907950Y1306000D03*
X910050D03*
Y1310000D03*
X907950D03*
X903850Y1328000D03*
X905950D03*
X907150Y1319000D03*
X909250D03*
X903850Y1324000D03*
X905950D03*
X907150Y1315000D03*
X909250D03*
X916950Y1324000D03*
Y1328000D03*
X903850Y1342000D03*
X905950D03*
X907150Y1337000D03*
X909250D03*
X907150Y1333000D03*
X909250D03*
X916950Y1342000D03*
X903850Y1346000D03*
X905950D03*
X916950D03*
X919450Y1310000D03*
X921550D03*
X919450Y1315000D03*
X921550D03*
X919450Y1319000D03*
X921550D03*
X919050Y1324000D03*
Y1328000D03*
Y1342000D03*
X919450Y1337000D03*
X921550D03*
X919450Y1333000D03*
X921550D03*
X919050Y1346000D03*
X942550Y1309500D03*
X940450D03*
X942550Y1305000D03*
X940450D03*
X942550Y1301500D03*
X940450D03*
X938450Y1328000D03*
X940550D03*
X938450Y1323500D03*
X940550D03*
X938450Y1314500D03*
X940550D03*
X938450Y1319000D03*
X940550D03*
X945550Y1314500D03*
X943450D03*
X945550Y1319000D03*
X943450D03*
X945550Y1323500D03*
X943450D03*
X945550Y1328000D03*
X943450D03*
X938450Y1337000D03*
X940550D03*
X938450Y1341500D03*
X940550D03*
X938450Y1332500D03*
X940550D03*
X945550D03*
X943450D03*
X945550Y1337000D03*
X943450D03*
X945550Y1341500D03*
X943450D03*
X938450Y1346000D03*
X940550D03*
X945550D03*
X943450D03*
X948322Y1309500D03*
X950422D03*
X948322Y1305500D03*
X950422D03*
X948322Y1301500D03*
X950422D03*
X966550Y1304200D03*
X968650D03*
X966550Y1307400D03*
X968650D03*
X977450Y1307500D03*
X979550D03*
X1006450Y1310500D03*
X1001450D03*
X1003550D03*
X1001450Y1303000D03*
X1003550D03*
X1001450Y1307000D03*
X1003550D03*
X1006450Y1315000D03*
Y1323840D03*
Y1319420D03*
Y1328260D03*
X1001450D03*
X1003550D03*
X1001450Y1323840D03*
X1003550D03*
X1001450Y1319420D03*
X1003550D03*
X1001450Y1315000D03*
X1003550D03*
X1006450Y1337160D03*
Y1332740D03*
Y1341580D03*
X1001450D03*
X1003550D03*
X1001450Y1332740D03*
X1003550D03*
X1001450Y1337160D03*
X1003550D03*
X1006450Y1346000D03*
X1001450D03*
X1003550D03*
X1008550Y1310500D03*
Y1315000D03*
Y1323840D03*
Y1319420D03*
Y1328260D03*
Y1337160D03*
Y1332740D03*
Y1341580D03*
Y1346000D03*
X1162009Y1669759D03*
X1164109D03*
X1161950Y1678500D03*
X1164050D03*
X1161950Y1673000D03*
X1164050D03*
X1161950Y1682000D03*
X1164050D03*
X1177161Y1542840D03*
X1179261D03*
X1177161Y1539640D03*
X1179261D03*
X1177161Y1552340D03*
X1179261D03*
X1177161Y1545940D03*
X1179261D03*
X1177161Y1549140D03*
X1179261D03*
X1177161Y1555540D03*
X1179261D03*
X1177826Y1682132D03*
X1175726D03*
X1185636Y1556820D03*
X1187736D03*
X1185518Y1675192D03*
X1187618D03*
X1185476Y1679128D03*
X1187576D03*
X1207750Y1685400D03*
X1209850D03*
X1201404D03*
X1203504D03*
X1201404Y1679000D03*
X1203504D03*
X1201404Y1675800D03*
X1203504D03*
X1201404Y1682200D03*
X1203504D03*
X1274346Y1559648D03*
X1272246D03*
X1282623Y1540400D03*
X1284723D03*
X1300223Y1551040D03*
X1302323D03*
X1300223Y1547420D03*
X1302323D03*
X1300223Y1543800D03*
X1302323D03*
X1305223Y1547420D03*
X1307323D03*
X1305223Y1543800D03*
X1307323D03*
X1305223Y1551040D03*
X1307323D03*
X1313698Y1556820D03*
X1315798D03*
X1402408Y1559648D03*
X1400308D03*
X1410685Y1540400D03*
X1412785D03*
X1436335Y1551040D03*
X1438435D03*
X1436335Y1547420D03*
X1438435D03*
X1436335Y1543800D03*
X1438435D03*
X1441335Y1547420D03*
X1443435D03*
X1441335Y1543800D03*
X1443435D03*
X1441335Y1551040D03*
X1443435D03*
X1449810Y1556820D03*
X1451910D03*
X1444232Y1667625D03*
X1446332D03*
X1449087Y1670759D03*
X1451187D03*
X1439292Y1665444D03*
X1441392D03*
X1453950Y1679000D03*
X1456050D03*
X1538520Y1559648D03*
X1536420D03*
X1546797Y1540400D03*
X1548897D03*
X1564397Y1551040D03*
X1566497D03*
X1569397Y1547420D03*
X1571497D03*
X1569397Y1543800D03*
X1571497D03*
X1564397Y1547420D03*
X1566497D03*
X1564397Y1543800D03*
X1566497D03*
X1569397Y1551040D03*
X1571497D03*
X1577872Y1556820D03*
X1579972D03*
X1658406Y1655648D03*
X1656306D03*
X1662305Y1662555D03*
X1660205D03*
X1649111Y1683441D03*
X1651211D03*
X1649066Y1680312D03*
X1651166D03*
X1648909Y1676470D03*
X1651009D03*
X1648552Y1687728D03*
X1650652D03*
X1661125Y1688021D03*
X1671327Y1542072D03*
X1673427D03*
X1663225Y1688021D03*
G54D28*
X48333Y444958D03*
X46759D03*
Y439446D03*
X48333D03*
G54D19*
X33000Y320983D03*
X43500D03*
X38733Y1613579D03*
X48167Y1632888D03*
X65397Y384611D03*
X57544Y399979D03*
X53738Y399953D03*
X56722Y438509D03*
X60761Y438442D03*
X60822Y524278D03*
X53742Y534748D03*
X60772Y534898D03*
X59503Y758815D03*
X69998Y384720D03*
X81667Y1611888D03*
X77667D03*
X99000Y1446983D03*
X186579Y1539121D03*
X182813Y1664979D03*
X182517Y1695046D03*
X196029Y1539121D03*
X200753D03*
X191304D03*
X210202D03*
X214926D03*
X205478D03*
X203660Y1671661D03*
X203807Y1686778D03*
X207660Y1678661D03*
X203807Y1701896D03*
X207807Y1693778D03*
X203807Y1708896D03*
X219651Y1539121D03*
X224375D03*
X229100D03*
X242220Y36845D03*
X246220D03*
X241787Y62823D03*
X234827Y699556D03*
X238548Y1539121D03*
X243273D03*
X254122Y36853D03*
X250220Y36845D03*
X246805Y62823D03*
X252722Y1539121D03*
X257446D03*
X247997D03*
X272870Y656063D03*
X267553Y662386D03*
X269871Y794971D03*
X262777Y1539121D03*
X290716Y45848D03*
X286716D03*
X293520Y18220D03*
X303720Y45845D03*
X300020D03*
X305600Y690304D03*
X300283Y696627D03*
X314641Y1539121D03*
X319366D03*
X333053Y716777D03*
X324091Y1539121D03*
X328815D03*
X333540D03*
X338370Y710454D03*
X342988Y1539121D03*
X338264D03*
X347713D03*
X362073Y597454D03*
X363313Y809158D03*
X359813D03*
X356313D03*
X363313Y817958D03*
X359813Y818058D03*
X356313D03*
X352813Y809158D03*
Y818058D03*
X361271Y1216471D03*
X357271D03*
X352437Y1539121D03*
X357162D03*
X371430Y710186D03*
X366113Y716509D03*
X366813Y809158D03*
X377313D03*
X373813D03*
X370313D03*
X366610Y1539121D03*
X371335D03*
X376059D03*
X395657Y552398D03*
X387657D03*
X391657D03*
X394271Y1071971D03*
X385508Y1539121D03*
X380784D03*
X390839D03*
X399657Y552398D03*
X403657D03*
X404470Y710254D03*
X399153Y716577D03*
X408500Y1649483D03*
X424874Y107595D03*
X420874D03*
X420748Y124843D03*
X423926Y1031987D03*
X420831Y1623642D03*
X416123Y1623663D03*
X411636Y1626807D03*
X412000Y1638983D03*
X432874Y107595D03*
X428874D03*
X436874D03*
X434990Y139625D03*
X431090D03*
X427190D03*
X438890D03*
X433710Y245648D03*
X437470Y692454D03*
X432153Y698777D03*
X440159Y970249D03*
Y977749D03*
Y985249D03*
X427666Y1031987D03*
X438886D03*
X431406D03*
X435146D03*
X428000Y1646483D03*
X440874Y107595D03*
X442790Y139625D03*
X442626Y1031987D03*
X450107D03*
X453847D03*
X446366D03*
X450752Y1539121D03*
X459457Y103947D03*
X455457D03*
X469870Y667854D03*
X464553Y674177D03*
X457587Y1031987D03*
X460202Y1539121D03*
X464926D03*
X469651D03*
X455477D03*
X457151Y1638925D03*
X457000Y1646983D03*
X476639Y315410D03*
X479099Y1539121D03*
X474375D03*
X483824D03*
X495652Y154528D03*
X499652D03*
X497153Y647677D03*
X488071Y1071771D03*
X488548Y1539121D03*
X493273D03*
X513618Y162931D03*
X502470Y641354D03*
X502721Y1539121D03*
X507446D03*
X512170D03*
X517618Y162931D03*
X525618D03*
X521618D03*
X518075Y840865D03*
X516895Y1539121D03*
X521619D03*
X526950D03*
X538968Y253618D03*
X535770Y607254D03*
X530453Y613577D03*
X544651Y650921D03*
X546350Y37068D03*
X548380Y133476D03*
X558968Y253618D03*
X564200Y55665D03*
X572200D03*
X568200Y55676D03*
X560200Y55671D03*
X567333Y69645D03*
X572171Y803371D03*
X576200Y55705D03*
X588968Y253618D03*
X587571Y803471D03*
X575671Y803371D03*
X578814Y1539121D03*
X588264D03*
X583539D03*
X602350Y55665D03*
X594405D03*
X590097D03*
X603771Y785871D03*
X591571Y796671D03*
X603261Y800423D03*
X602201Y1237558D03*
X597971Y1246971D03*
X602437Y1539121D03*
X592988D03*
X597713D03*
X614845Y55665D03*
X610285D03*
X606330D03*
X615571Y785871D03*
X606201Y1237558D03*
X612171Y1245771D03*
X607161Y1539121D03*
X616610D03*
X611886D03*
X627496Y80444D03*
X630783Y1539121D03*
X621335D03*
X647672Y36969D03*
X634220Y61948D03*
X645222Y55243D03*
X640670Y80444D03*
X646719Y430920D03*
X644957Y1539121D03*
X635508D03*
X640232D03*
X643258Y1696753D03*
X647258Y1710753D03*
X643258Y1703753D03*
Y1717753D03*
X651910Y36969D03*
X649222Y55243D03*
X659045Y417844D03*
X658603Y1369987D03*
X649681Y1539121D03*
X655012D03*
X675500Y387845D03*
X668058Y1717435D03*
X690291Y57815D03*
X683500Y387845D03*
X679500D03*
X702481Y55641D03*
X698597Y55665D03*
X694400D03*
X707849Y130176D03*
X708652Y500827D03*
X700652D03*
X704652D03*
X705815Y1660439D03*
X709303Y56194D03*
X720010Y81712D03*
X716033D03*
X712043D03*
X719438Y383817D03*
X715500Y396345D03*
X711500D03*
X719500D03*
X708800Y421603D03*
X712652Y500827D03*
X720652D03*
X711344Y525315D03*
X718381Y528424D03*
X718500Y574483D03*
X714090Y1603526D03*
X717694Y1604711D03*
X713317Y1627269D03*
X709317Y1637769D03*
X709771Y1660448D03*
X717749Y1660442D03*
X722630Y1666881D03*
X724000Y81712D03*
X727500Y396345D03*
X724652Y500827D03*
X733191Y519422D03*
X729624Y527377D03*
X725424Y528221D03*
X733160Y525924D03*
X726302Y1663721D03*
X730302D03*
X747500Y396345D03*
X742956Y539507D03*
X748482Y554493D03*
X753010Y1579081D03*
Y1587081D03*
X763500Y383845D03*
X767500D03*
X759500Y396345D03*
X763500D03*
X760517Y554367D03*
X791500Y544483D03*
X785500Y539483D03*
X785000Y569483D03*
X789000D03*
X808220Y143045D03*
X821120Y142445D03*
X841720Y215845D03*
X837500Y226135D03*
X858528Y267865D03*
X899707Y1139541D03*
X915500Y859983D03*
X905500D03*
X910500D03*
X903843Y899685D03*
X909000Y915483D03*
X913000D03*
X905000D03*
X925500Y922983D03*
X918780Y1666245D03*
X931798D03*
X923798D03*
X927798D03*
X934000Y863983D03*
X943000Y858483D03*
X938000D03*
X946500Y922983D03*
X938500D03*
X946732Y1139541D03*
X939798Y1666245D03*
X935798D03*
X949500Y883483D03*
X954500Y922983D03*
X948500Y933983D03*
X961023Y1509106D03*
X947798Y1666245D03*
X951798D03*
X984555Y180466D03*
X1016567Y210611D03*
X1123228Y1656406D03*
X1118402Y1656961D03*
X1134649Y1656528D03*
X1194452Y1572121D03*
X1199177D03*
X1214094Y264116D03*
X1203902Y1572121D03*
X1208626D03*
X1213351D03*
X1230094Y264116D03*
X1222094D03*
Y311624D03*
X1222799Y1572121D03*
X1218075D03*
X1227524D03*
X1238094Y264116D03*
X1240177Y796471D03*
X1235177D03*
X1232248Y1572121D03*
X1236973D03*
X1254094Y264116D03*
X1246094D03*
X1247785Y303215D03*
X1251146Y1572121D03*
X1246421D03*
X1255870D03*
X1262094Y264116D03*
X1270094D03*
X1269177Y804307D03*
X1260677D03*
X1260595Y1572121D03*
X1265319D03*
X1270650D03*
X1286094Y264116D03*
X1278094D03*
X1282677Y797207D03*
X1286677D03*
X1282677Y804307D03*
X1294094Y264116D03*
X1302094D03*
X1318094D03*
X1310094D03*
X1307824Y596494D03*
X1326094Y264116D03*
X1334094D03*
X1332877Y847471D03*
X1333977Y1218861D03*
X1322514Y1572121D03*
X1331964D03*
X1327239D03*
X1342094Y264116D03*
X1346717Y669371D03*
X1336877Y847471D03*
X1346137Y1572121D03*
X1336688D03*
X1341413D03*
X1358094Y264116D03*
X1350094D03*
X1350861Y1572121D03*
X1360310D03*
X1355586D03*
X1366094Y264116D03*
X1378105Y631720D03*
X1370477Y1071871D03*
X1374483Y1572121D03*
X1379208D03*
X1365035D03*
X1383422Y625397D03*
X1393381Y1572121D03*
X1388657D03*
X1383932D03*
X1400068Y1031986D03*
X1403808D03*
X1407548D03*
X1398712Y1572121D03*
X1396901Y1657491D03*
X1416122Y658297D03*
X1410805Y664620D03*
X1416301Y970248D03*
Y977748D03*
Y985248D03*
X1422508Y1031986D03*
X1418768D03*
X1411288D03*
X1415028D03*
X1433729D03*
X1426249D03*
X1429989D03*
X1448722Y690877D03*
X1443405Y697200D03*
X1465832Y540885D03*
X1461159Y846065D03*
X1465559D03*
X1464177Y1071771D03*
X1468076Y1572121D03*
X1458626D03*
X1463351D03*
X1475473Y588316D03*
X1481640Y710454D03*
X1476323Y716777D03*
X1477177Y808971D03*
X1473177D03*
X1478177Y822471D03*
X1482177D03*
X1483159Y846065D03*
X1478759D03*
X1474359D03*
X1469959D03*
X1482249Y1572121D03*
X1472800D03*
X1477525D03*
X1489177Y808971D03*
X1498177Y822471D03*
X1494177D03*
X1487559Y846065D03*
X1491959D03*
X1496359D03*
X1486973Y1572121D03*
X1491698D03*
X1496422D03*
X1508757Y542960D03*
X1500757D03*
X1504757D03*
X1512757D03*
X1509405Y716777D03*
X1500759Y846065D03*
X1510595Y1572121D03*
X1501147D03*
X1516757Y542960D03*
X1514722Y710454D03*
X1515320Y1572121D03*
X1524769D03*
X1520044D03*
X1542205Y716777D03*
X1539782Y1238414D03*
X1529493Y1572121D03*
X1534824D03*
X1547522Y710454D03*
X1555603Y791891D03*
X1550432Y791809D03*
X1543772Y1238384D03*
X1567836Y573930D03*
X1559618Y791857D03*
X1569148Y1344681D03*
X1572924D03*
X1572906Y1359161D03*
X1580652Y688514D03*
X1575335Y694837D03*
X1579205Y1306052D03*
X1580924Y1344681D03*
Y1359161D03*
X1586688Y1572121D03*
X1592852Y1304041D03*
X1596138Y1572121D03*
X1600862D03*
X1591413D03*
X1609141Y598389D03*
X1613422Y654745D03*
X1608105Y661068D03*
X1608652Y1292296D03*
Y1300646D03*
X1610311Y1572121D03*
X1615035D03*
X1605587D03*
X1620379Y550418D03*
X1624484Y1572121D03*
X1619760D03*
X1629209D03*
X1646422Y635745D03*
X1641105Y642068D03*
X1643382Y1572121D03*
X1638657D03*
X1655147Y679791D03*
X1657555Y1572121D03*
X1652831D03*
X1648106D03*
X1662886D03*
X1690560Y430095D03*
X1680147Y1311041D03*
X1685383Y1719651D03*
Y1726651D03*
X1712799Y107335D03*
X1710230Y1726333D03*
X1750463Y1649448D03*
X1762062Y43086D03*
X1755463Y1649448D03*
X1773757Y34383D03*
X1777754Y43352D03*
X1773554Y43192D03*
X1769900D03*
X1781990Y43238D03*
X1787672Y53069D03*
X1791672D03*
X1807296Y260516D03*
G54D91*
X735086Y448279D03*
Y445129D03*
X725718Y448279D03*
Y445129D03*
X730152Y448279D03*
Y445129D03*
X725718Y463948D03*
X735086Y463949D03*
Y460799D03*
X730152Y463948D03*
X725718Y467098D03*
X730152D03*
X738236Y463949D03*
Y460799D03*
G54D73*
X609016Y274272D03*
G54D82*
X695796Y430957D03*
Y437256D03*
Y468672D03*
X708395Y427807D03*
X705245Y437256D03*
X698946Y449854D03*
X708395Y456074D03*
Y478121D03*
Y471822D03*
Y484420D03*
X717843Y434106D03*
X720993Y427807D03*
Y468672D03*
X724143Y471822D03*
X714694Y468672D03*
X711544Y474971D03*
X724143Y481271D03*
X720993Y484420D03*
X727292Y424657D03*
X739811Y430957D03*
X733512Y471822D03*
X727292Y487570D03*
X755559Y421508D03*
X749260Y427807D03*
X752409Y440405D03*
Y462373D03*
X746110Y474971D03*
X752409Y478121D03*
X758709Y427807D03*
Y434106D03*
Y465523D03*
Y459223D03*
X765008Y474971D03*
X758709Y478121D03*
G54D65*
X434513Y978703D03*
X1410419D03*
G54D47*
X274913Y1019214D03*
X320189Y838505D03*
Y1199923D03*
X561133Y838505D03*
Y1199923D03*
X606409Y1019214D03*
X841240Y1420331D03*
X1016240D03*
X1251055Y1019213D03*
X1296331Y838504D03*
Y1199922D03*
X1537275Y838504D03*
Y1199922D03*
X1582551Y1019213D03*
G54D92*
X736260Y1653665D03*
X733760Y1672685D03*
X737500D03*
X733760Y1683315D03*
X740000Y1644335D03*
X743740Y1653665D03*
X741240Y1672685D03*
Y1683315D03*
G54D74*
X630328Y1640413D03*
Y1647027D03*
X916763Y981782D03*
Y975168D03*
X1175454Y1671059D03*
Y1677673D03*
X1661035Y1676874D03*
Y1683488D03*
G54D29*
X39361Y539285D03*
X46361D03*
X65823Y758505D03*
X67522Y1564789D03*
Y1557889D03*
X67435Y1578558D03*
X67522Y1571689D03*
X54927Y1648887D03*
X61927D03*
X81965Y758505D03*
X72823D03*
X74522Y1564789D03*
Y1557889D03*
X74435Y1578558D03*
X74522Y1571689D03*
X88965Y758505D03*
X95524D03*
X111666D03*
X102524D03*
X125225D03*
X118666D03*
X117190Y1390210D03*
X124190D03*
X141367Y758505D03*
X132225D03*
X134685Y1672333D03*
X141685D03*
X148367Y758505D03*
X154926D03*
X171068D03*
X161926D03*
X184626D03*
X178068D03*
X177322Y1502450D03*
X184322D03*
X200768Y758505D03*
X191626D03*
X207768D03*
X214327D03*
X227415Y597556D03*
Y589456D03*
X227433Y605598D03*
X230469Y758505D03*
X221327D03*
X234415Y597556D03*
Y589456D03*
X234433Y605598D03*
X237469Y758505D03*
X253166Y67826D03*
X260166D03*
X251969Y78930D03*
X258969D03*
X271546Y1535721D03*
Y1542575D03*
X278546Y1535721D03*
X291568Y1537746D03*
X291542Y1530892D03*
X278546Y1542575D03*
X303872Y1500938D03*
X298568Y1537746D03*
X298542Y1530892D03*
X310872Y1500938D03*
X406608Y1535721D03*
X399608D03*
X406608Y1542575D03*
X399608D03*
X439902Y1501267D03*
X427653Y1530892D03*
X434653D03*
X427679Y1537746D03*
X434679D03*
X451599Y120007D03*
X446902Y1501267D03*
X458599Y120007D03*
X508723Y285010D03*
X515723D03*
X508723Y301115D03*
X515723D03*
X508723Y293060D03*
X515723D03*
X508723Y309170D03*
X515723D03*
X542619Y1535721D03*
X535619D03*
X542619Y1542575D03*
X535619D03*
X555741Y1537746D03*
X555715Y1530892D03*
X568142Y1501985D03*
X575142D03*
X562741Y1537746D03*
X562715Y1530892D03*
X595723Y294010D03*
X602723D03*
X595723Y310115D03*
X602723D03*
X595723Y302060D03*
X602723D03*
X595723Y318170D03*
X602723D03*
X643855Y758505D03*
X650855D03*
X659997D03*
X673556D03*
X666997D03*
X685420Y97062D03*
X692420D03*
X680556Y758505D03*
X689698D03*
X703257D03*
X696698D03*
X710257D03*
X719399D03*
X726399D03*
X732957D03*
X725641Y1408138D03*
X732641D03*
X725500Y1415500D03*
X732500D03*
X725500Y1430150D03*
X732500D03*
X749099Y758505D03*
X739957D03*
X756099D03*
X762658D03*
X769658D03*
X778800D03*
X783673Y1355396D03*
Y1362296D03*
X792359Y758504D03*
X785800Y758505D03*
X790673Y1355396D03*
Y1362296D03*
X799359Y758504D03*
X808500D03*
X815500D03*
X1018144Y1284787D03*
X1011144D03*
X1048965Y758504D03*
X1041965D03*
X1058107D03*
X1065107D03*
X1078666D03*
X1071666D03*
X1087808D03*
X1094808D03*
X1108367D03*
X1101367D03*
X1117509D03*
X1124509D03*
X1138068D03*
X1131068D03*
X1147210D03*
X1154210D03*
X1167768D03*
X1160768D03*
X1176910D03*
X1183910D03*
X1183752Y1533247D03*
X1197469Y758504D03*
X1190469D03*
X1190752Y1533247D03*
X1206611Y758504D03*
X1213611D03*
X1286419Y1568721D03*
X1279419D03*
X1286419Y1575575D03*
X1279419D03*
X1299415Y1563892D03*
X1299441Y1570746D03*
X1320436Y614409D03*
Y607309D03*
X1311852Y1535345D03*
X1318852D03*
X1306415Y1563892D03*
X1306441Y1570746D03*
X1327436Y614409D03*
Y607309D03*
X1407481Y1568721D03*
Y1575575D03*
X1414481Y1568721D03*
Y1575575D03*
X1435527Y1563892D03*
X1435553Y1570746D03*
X1448082Y1535743D03*
X1455082D03*
X1442527Y1563892D03*
X1442553Y1570746D03*
X1543593Y1568721D03*
Y1575575D03*
X1555087Y671098D03*
X1550593Y1568721D03*
Y1575575D03*
X1562087Y671098D03*
X1563589Y1563892D03*
X1570589D03*
X1563615Y1570746D03*
X1570615D03*
X1575992Y1535571D03*
X1582992D03*
X1626996Y758504D03*
X1619996D03*
X1636138D03*
X1643138D03*
X1656697D03*
X1649697D03*
X1665839D03*
X1672839D03*
X1673258Y1411694D03*
X1686398Y758504D03*
X1679398D03*
X1680258Y1411694D03*
X1695540Y758504D03*
X1702540D03*
X1716099D03*
X1709099D03*
X1730096Y63051D03*
X1737096D03*
X1729389Y86348D03*
X1736389D03*
X1725241Y758504D03*
X1732241D03*
X1733500Y1402500D03*
X1726500D03*
X1745799Y758504D03*
X1738799D03*
X1754941D03*
X1761941D03*
X1757279Y1597550D03*
X1764279D03*
X1757279Y1604950D03*
X1764279D03*
X1775500Y758504D03*
X1768500D03*
X1784642D03*
X1791642D03*
X1808013Y1598316D03*
X1801013D03*
X1808013Y1605816D03*
X1801013D03*
G54D38*
X186530Y1521653D03*
X185720Y1518770D03*
Y1516670D03*
X186530Y1523753D03*
X177559Y1528907D03*
Y1531007D03*
X200703Y1521653D03*
X191254D03*
X195979D03*
X201254Y1528653D03*
Y1526553D03*
X200703Y1523753D03*
X191805Y1528653D03*
Y1526553D03*
X196530Y1528653D03*
Y1526553D03*
X191254Y1523753D03*
X195979D03*
X187081Y1528653D03*
Y1526553D03*
X194096Y1607286D03*
Y1609386D03*
X197696Y1607286D03*
Y1609386D03*
X214876Y1521653D03*
X210152D03*
X205427D03*
X214876Y1523753D03*
X210152D03*
X205978Y1528653D03*
Y1526553D03*
X210703Y1528653D03*
Y1526553D03*
X205427Y1523753D03*
X215427Y1528653D03*
Y1526553D03*
X206156Y1607286D03*
Y1609386D03*
X209756Y1607286D03*
Y1609386D03*
X229049Y1521653D03*
X224325D03*
X219601D03*
X229049Y1523753D03*
X224876Y1528653D03*
Y1526553D03*
X224325Y1523753D03*
X219601D03*
X229600Y1528653D03*
Y1526553D03*
X220152Y1528653D03*
Y1526553D03*
X230276Y1607286D03*
Y1609386D03*
X218216Y1607286D03*
Y1609386D03*
X221816Y1607286D03*
Y1609386D03*
X243223Y1521653D03*
X233774D03*
X238498D03*
X234325Y1528653D03*
Y1526553D03*
X243223Y1523753D03*
X233774D03*
X238498D03*
X239049Y1528653D03*
Y1526553D03*
X243774Y1528653D03*
Y1526553D03*
X233824Y1537963D03*
Y1540063D03*
X242336Y1607286D03*
Y1609386D03*
X245936Y1607286D03*
Y1609386D03*
X233876Y1607286D03*
Y1609386D03*
X252672Y1521653D03*
X257396D03*
X247947D03*
X252672Y1523753D03*
X253223Y1528653D03*
Y1526553D03*
X257947Y1528653D03*
Y1526553D03*
X257396Y1523753D03*
X248498Y1528653D03*
Y1526553D03*
X247947Y1523753D03*
X254396Y1607286D03*
Y1609386D03*
X257996Y1607286D03*
Y1609386D03*
X262141Y1521653D03*
Y1523753D03*
X266456Y1607286D03*
Y1609386D03*
X270056Y1607286D03*
Y1609386D03*
X290576Y1607286D03*
Y1609386D03*
X282116Y1607286D03*
Y1609386D03*
X278516Y1607286D03*
Y1609386D03*
X305621Y1528907D03*
Y1531007D03*
X302636Y1607286D03*
Y1609386D03*
X294176Y1607286D03*
Y1609386D03*
X314592Y1521653D03*
X319316D03*
X313782Y1518770D03*
Y1516670D03*
X319867Y1528653D03*
Y1526553D03*
X314592Y1523753D03*
X319316D03*
X315143Y1528653D03*
Y1526553D03*
X318296Y1607286D03*
Y1609386D03*
X314696Y1607286D03*
Y1609386D03*
X306236Y1607286D03*
Y1609386D03*
X333489Y1521653D03*
X328765D03*
X324041D03*
X333489Y1523753D03*
X334040Y1528653D03*
Y1526553D03*
X324592Y1528653D03*
Y1526553D03*
X328765Y1523753D03*
X329316Y1528653D03*
Y1526553D03*
X324041Y1523753D03*
X326756Y1607286D03*
Y1609386D03*
X330356Y1607286D03*
Y1609386D03*
X342938Y1521653D03*
X347663D03*
X338214D03*
X348214Y1528653D03*
Y1526553D03*
X343489Y1528653D03*
Y1526553D03*
X342938Y1523753D03*
X347663D03*
X338214D03*
X338765Y1528653D03*
Y1526553D03*
X338816Y1607286D03*
Y1609386D03*
X342416Y1607286D03*
Y1609386D03*
X352387Y1521653D03*
X357111D03*
X361836D03*
X352387Y1523753D03*
X352938Y1528653D03*
Y1526553D03*
X357111Y1523753D03*
X361836D03*
X362387Y1528653D03*
Y1526553D03*
X357662Y1528653D03*
Y1526553D03*
X361886Y1537963D03*
Y1540063D03*
X362936Y1607286D03*
Y1609386D03*
X350876Y1607286D03*
Y1609386D03*
X354476Y1607286D03*
Y1609386D03*
X366560Y1521653D03*
X376009D03*
X371285D03*
X366560Y1523753D03*
X367111Y1528653D03*
Y1526553D03*
X376560Y1528653D03*
Y1526553D03*
X376009Y1523753D03*
X371285D03*
X371836Y1528653D03*
Y1526553D03*
X374996Y1607286D03*
Y1609386D03*
X378596Y1607286D03*
Y1609386D03*
X366536Y1607286D03*
Y1609386D03*
X385458Y1521653D03*
X380734D03*
X390203D03*
X385458Y1523753D03*
X386009Y1528653D03*
Y1526553D03*
X380734Y1523753D03*
X381285Y1528653D03*
Y1526553D03*
X390203Y1523753D03*
X450703Y1521653D03*
X449893Y1518770D03*
Y1516670D03*
X450703Y1523753D03*
X451254Y1528653D03*
Y1526553D03*
X442340Y1609914D03*
Y1607814D03*
X445570Y1609784D03*
Y1607684D03*
X469600Y1521653D03*
X460152D03*
X455427D03*
X464876D03*
X469600Y1523753D03*
X460152D03*
X465427Y1528653D03*
Y1526553D03*
X460703Y1528653D03*
Y1526553D03*
X455427Y1523753D03*
X455978Y1528653D03*
Y1526553D03*
X464876Y1523753D03*
X461869Y1607286D03*
Y1609386D03*
X458269Y1607286D03*
Y1609386D03*
X483774Y1521653D03*
X479049D03*
X474325D03*
X479600Y1528653D03*
Y1526553D03*
X484325Y1528653D03*
Y1526553D03*
X483774Y1523753D03*
X479049D03*
X470151Y1528653D03*
Y1526553D03*
X474325Y1523753D03*
X474876Y1528653D03*
Y1526553D03*
X482389Y1607286D03*
Y1609386D03*
X470329Y1607286D03*
Y1609386D03*
X473929Y1607286D03*
Y1609386D03*
X488498Y1521653D03*
X493222D03*
X497947D03*
X488498Y1523753D03*
X489049Y1528653D03*
Y1526553D03*
X493222Y1523753D03*
X493773Y1528653D03*
Y1526553D03*
X497947Y1523753D03*
X498498Y1528653D03*
Y1526553D03*
X497997Y1537963D03*
Y1540063D03*
X494449Y1607286D03*
Y1609386D03*
X498049Y1607286D03*
Y1609386D03*
X485989Y1607286D03*
Y1609386D03*
X502671Y1521653D03*
X512120D03*
X507396D03*
X502671Y1523753D03*
X503222Y1528653D03*
Y1526553D03*
X507947Y1528653D03*
Y1526553D03*
X512120Y1523753D03*
X507396D03*
X512671Y1528653D03*
Y1526553D03*
X506509Y1607286D03*
Y1609386D03*
X510109Y1607286D03*
Y1609386D03*
X516845Y1521653D03*
X521569D03*
X526314D03*
X516845Y1523753D03*
X521569D03*
X526314D03*
X517396Y1528653D03*
Y1526553D03*
X522120Y1528653D03*
Y1526553D03*
X518569Y1607286D03*
Y1609386D03*
X522169Y1607286D03*
Y1609386D03*
X542689Y1607286D03*
Y1609386D03*
X530629Y1607286D03*
Y1609386D03*
X534229Y1607286D03*
Y1609386D03*
X554749Y1607286D03*
Y1609386D03*
X558349Y1607286D03*
Y1609386D03*
X546289Y1607286D03*
Y1609386D03*
X569794Y1528907D03*
Y1531007D03*
X566809Y1607286D03*
Y1609386D03*
X570409Y1607286D03*
Y1609386D03*
X577955Y1518770D03*
Y1516670D03*
X578765Y1521653D03*
X588214D03*
X583489D03*
X578765Y1523753D03*
X588765Y1528653D03*
Y1526553D03*
X588214Y1523753D03*
X579316Y1528653D03*
Y1526553D03*
X584040Y1528653D03*
Y1526553D03*
X583489Y1523753D03*
X578869Y1607286D03*
Y1609386D03*
X582469Y1607286D03*
Y1609386D03*
X597662Y1521653D03*
X592938D03*
X602387D03*
X597662Y1523753D03*
X598213Y1528653D03*
Y1526553D03*
X592938Y1523753D03*
X593489Y1528653D03*
Y1526553D03*
X602938Y1528653D03*
Y1526553D03*
X602387Y1523753D03*
X602989Y1607286D03*
Y1609386D03*
X590929Y1607286D03*
Y1609386D03*
X594529Y1607286D03*
Y1609386D03*
X611836Y1521653D03*
X616560D03*
X607111D03*
X607662Y1528653D03*
Y1526553D03*
X612387Y1528653D03*
Y1526553D03*
X611836Y1523753D03*
X617111Y1528653D03*
Y1526553D03*
X616560Y1523753D03*
X607111D03*
X615049Y1607286D03*
Y1609386D03*
X618649Y1607286D03*
Y1609386D03*
X606589Y1607286D03*
Y1609386D03*
X630733Y1521653D03*
X621284D03*
X626009D03*
X630733Y1523753D03*
X631284Y1528653D03*
Y1526553D03*
X621284Y1523753D03*
X621835Y1528653D03*
Y1526553D03*
X626560Y1528653D03*
Y1526553D03*
X626009Y1523753D03*
X626059Y1537963D03*
Y1540063D03*
X627109Y1607286D03*
Y1609386D03*
X630709Y1607286D03*
Y1609386D03*
X644907Y1521653D03*
X635458D03*
X640182D03*
X640733Y1528653D03*
Y1526553D03*
X644907Y1523753D03*
X635458D03*
X640182D03*
X636009Y1528653D03*
Y1526553D03*
X645458Y1528653D03*
Y1526553D03*
X639169Y1607286D03*
Y1609386D03*
X642769Y1607286D03*
Y1609386D03*
X643400Y1623840D03*
Y1621740D03*
X643580Y1629150D03*
Y1627050D03*
X646092Y1655321D03*
Y1653221D03*
X643800Y1670605D03*
X647000D03*
X640600D03*
X647500Y1677750D03*
Y1679850D03*
X643800Y1672705D03*
X647000D03*
X640600D03*
X649631Y1521653D03*
X654376D03*
X649960Y1514040D03*
Y1511940D03*
X649631Y1523753D03*
X654376D03*
X650182Y1528653D03*
Y1526553D03*
X649216Y1655321D03*
Y1653221D03*
X655406Y1671476D03*
X650200Y1670605D03*
X662600Y1657524D03*
Y1659624D03*
X655406Y1673576D03*
X650200Y1672705D03*
X666200Y1657524D03*
Y1659624D03*
X670962Y1667450D03*
Y1669550D03*
X670830Y1672389D03*
Y1674489D03*
X850500Y1313450D03*
Y1320550D03*
Y1318450D03*
X854000Y1322450D03*
Y1324550D03*
Y1327450D03*
X850500Y1315550D03*
X854000Y1329550D03*
X850500Y1331450D03*
Y1333550D03*
Y1338550D03*
Y1336450D03*
X854000Y1340450D03*
Y1342550D03*
Y1347550D03*
Y1345450D03*
X915500Y1313450D03*
X912000Y1322450D03*
Y1324550D03*
Y1327450D03*
X915500Y1320550D03*
Y1318450D03*
Y1315550D03*
X912000Y1340450D03*
Y1342550D03*
X915500Y1338550D03*
Y1336450D03*
Y1331450D03*
Y1333550D03*
X912000Y1329550D03*
Y1347550D03*
Y1345450D03*
X1185432Y1561907D03*
Y1564007D03*
X1185363Y1684784D03*
Y1682684D03*
X1193593Y1551770D03*
Y1549670D03*
X1199127Y1554653D03*
Y1556753D03*
X1194403Y1554653D03*
Y1556753D03*
X1199678Y1561653D03*
Y1559553D03*
X1194954Y1561653D03*
Y1559553D03*
X1187147Y1670012D03*
Y1672112D03*
X1213851Y1561653D03*
Y1559553D03*
X1213300Y1554653D03*
Y1556753D03*
X1209127Y1561653D03*
Y1559553D03*
X1203852Y1554653D03*
Y1556753D03*
X1208576Y1554653D03*
Y1556753D03*
X1204403Y1561653D03*
Y1559553D03*
X1214029Y1640286D03*
X1205569D03*
X1201969D03*
X1214029Y1642386D03*
X1205569D03*
X1201969D03*
X1223300Y1561653D03*
Y1559553D03*
X1228025Y1561653D03*
Y1559553D03*
X1227474Y1554653D03*
Y1556753D03*
X1222749Y1554653D03*
Y1556753D03*
X1218576Y1561653D03*
Y1559553D03*
X1218025Y1554653D03*
Y1556753D03*
X1229689Y1640286D03*
X1226089D03*
X1217629D03*
X1229689Y1642386D03*
X1226089D03*
X1217629D03*
X1232198Y1554653D03*
Y1556753D03*
X1232749Y1561653D03*
Y1559553D03*
X1236922Y1554653D03*
Y1556753D03*
X1241647Y1554653D03*
Y1556753D03*
X1242198Y1561653D03*
Y1559553D03*
X1237473Y1561653D03*
Y1559553D03*
X1241697Y1570963D03*
Y1573063D03*
X1241749Y1640286D03*
X1238149D03*
X1241749Y1642386D03*
X1238149D03*
X1246922Y1561653D03*
Y1559553D03*
X1246371Y1554653D03*
Y1556753D03*
X1251096Y1554653D03*
Y1556753D03*
X1255820Y1554653D03*
Y1556753D03*
X1251647Y1561653D03*
Y1559553D03*
X1256371Y1561653D03*
Y1559553D03*
X1253809Y1640286D03*
X1250209D03*
X1253809Y1642386D03*
X1250209D03*
X1265269Y1554653D03*
Y1556753D03*
X1261096Y1561653D03*
Y1559553D03*
X1260545Y1554653D03*
Y1556753D03*
X1270014Y1554653D03*
Y1556753D03*
X1265820Y1561653D03*
Y1559553D03*
X1274329Y1640286D03*
X1265869D03*
X1262269D03*
X1274329Y1642386D03*
X1265869D03*
X1262269D03*
X1286389Y1640286D03*
X1277929D03*
X1286389Y1642386D03*
X1277929D03*
X1302049Y1640286D03*
X1298449D03*
X1289989D03*
X1302049Y1642386D03*
X1298449D03*
X1289989D03*
X1313494Y1561907D03*
Y1564007D03*
X1314109Y1640286D03*
X1310509D03*
X1314109Y1642386D03*
X1310509D03*
X1321655Y1551770D03*
Y1549670D03*
X1332465Y1561653D03*
Y1559553D03*
X1327189Y1554653D03*
Y1556753D03*
X1331914Y1554653D03*
Y1556753D03*
X1322465Y1554653D03*
Y1556753D03*
X1323016Y1561653D03*
Y1559553D03*
X1327740Y1561653D03*
Y1559553D03*
X1334629Y1640286D03*
X1326169D03*
X1322569D03*
X1334629Y1642386D03*
X1326169D03*
X1322569D03*
X1341913Y1561653D03*
Y1559553D03*
X1341362Y1554653D03*
Y1556753D03*
X1336638Y1554653D03*
Y1556753D03*
X1337189Y1561653D03*
Y1559553D03*
X1346638Y1561653D03*
Y1559553D03*
X1346087Y1554653D03*
Y1556753D03*
X1346689Y1640286D03*
X1338229D03*
X1346689Y1642386D03*
X1338229D03*
X1351362Y1561653D03*
Y1559553D03*
X1356087Y1561653D03*
Y1559553D03*
X1350811Y1554653D03*
Y1556753D03*
X1360260Y1554653D03*
Y1556753D03*
X1355536Y1554653D03*
Y1556753D03*
X1360811Y1561653D03*
Y1559553D03*
X1362349Y1640286D03*
X1358749D03*
X1350289D03*
X1362349Y1642386D03*
X1358749D03*
X1350289D03*
X1374984Y1561653D03*
Y1559553D03*
X1374433Y1554653D03*
Y1556753D03*
X1364984Y1554653D03*
Y1556753D03*
X1379158Y1554653D03*
Y1556753D03*
X1365535Y1561653D03*
Y1559553D03*
X1370260Y1561653D03*
Y1559553D03*
X1369709Y1554653D03*
Y1556753D03*
X1369759Y1570963D03*
Y1573063D03*
X1374409Y1640286D03*
X1370809D03*
X1374409Y1642386D03*
X1370809D03*
X1383882Y1554653D03*
Y1556753D03*
X1379709Y1561653D03*
Y1559553D03*
X1389158Y1561653D03*
Y1559553D03*
X1388607Y1554653D03*
Y1556753D03*
X1393331Y1554653D03*
Y1556753D03*
X1384433Y1561653D03*
Y1559553D03*
X1393882Y1561653D03*
Y1559553D03*
X1386469Y1640286D03*
X1382869D03*
X1386469Y1642386D03*
X1382869D03*
X1398076Y1554653D03*
Y1556753D03*
X1449606Y1561907D03*
Y1564007D03*
X1450980Y1677333D03*
Y1675233D03*
X1457767Y1551770D03*
Y1549670D03*
X1468026Y1554653D03*
Y1556753D03*
X1458577Y1554653D03*
Y1556753D03*
X1463301Y1554653D03*
Y1556753D03*
X1463852Y1561653D03*
Y1559553D03*
X1468577Y1561653D03*
Y1559553D03*
X1459128Y1561653D03*
Y1559553D03*
X1466143Y1640286D03*
Y1642386D03*
X1477474Y1554653D03*
Y1556753D03*
X1478025Y1561653D03*
Y1559553D03*
X1472750Y1554653D03*
Y1556753D03*
X1473301Y1561653D03*
Y1559553D03*
X1482199Y1554653D03*
Y1556753D03*
X1482750Y1561653D03*
Y1559553D03*
X1481803Y1640286D03*
X1478203D03*
X1469743D03*
X1481803Y1642386D03*
X1478203D03*
X1469743D03*
X1492199Y1561653D03*
Y1559553D03*
X1487474Y1561653D03*
Y1559553D03*
X1486923Y1554653D03*
Y1556753D03*
X1496372Y1554653D03*
Y1556753D03*
X1491648Y1554653D03*
Y1556753D03*
X1496923Y1561653D03*
Y1559553D03*
X1493863Y1640286D03*
X1490263D03*
X1493863Y1642386D03*
X1490263D03*
X1511096Y1561653D03*
Y1559553D03*
X1510545Y1554653D03*
Y1556753D03*
X1501096Y1554653D03*
Y1556753D03*
X1501647Y1561653D03*
Y1559553D03*
X1505821Y1554653D03*
Y1556753D03*
X1506372Y1561653D03*
Y1559553D03*
X1505871Y1570963D03*
Y1573063D03*
X1505923Y1640286D03*
X1502323D03*
X1505923Y1642386D03*
X1502323D03*
X1524719Y1554653D03*
Y1556753D03*
X1525270Y1561653D03*
Y1559553D03*
X1519994Y1554653D03*
Y1556753D03*
X1515270Y1554653D03*
Y1556753D03*
X1520545Y1561653D03*
Y1559553D03*
X1515821Y1561653D03*
Y1559553D03*
X1526443Y1640286D03*
X1517983D03*
X1514383D03*
X1526443Y1642386D03*
X1517983D03*
X1514383D03*
X1529994Y1561653D03*
Y1559553D03*
X1529443Y1554653D03*
Y1556753D03*
X1534188Y1554653D03*
Y1556753D03*
X1542103Y1640286D03*
X1538503D03*
X1530043D03*
X1542103Y1642386D03*
X1538503D03*
X1530043D03*
X1554163Y1640286D03*
X1550563D03*
X1554163Y1642386D03*
X1550563D03*
X1566223Y1640286D03*
X1562623D03*
X1566223Y1642386D03*
X1562623D03*
X1585829Y1551770D03*
Y1549670D03*
X1577668Y1561907D03*
Y1564007D03*
X1587190Y1561653D03*
Y1559553D03*
X1586639Y1554653D03*
Y1556753D03*
X1586743Y1640286D03*
X1578283D03*
X1574683D03*
X1586743Y1642386D03*
X1578283D03*
X1574683D03*
X1600812Y1554653D03*
Y1556753D03*
X1591363Y1554653D03*
Y1556753D03*
X1591914Y1561653D03*
Y1559553D03*
X1596639Y1561653D03*
Y1559553D03*
X1596088Y1554653D03*
Y1556753D03*
X1601363Y1561653D03*
Y1559553D03*
X1602403Y1640286D03*
X1598803D03*
X1590343D03*
X1602403Y1642386D03*
X1598803D03*
X1590343D03*
X1615536Y1561653D03*
Y1559553D03*
X1614985Y1554653D03*
Y1556753D03*
X1605536Y1554653D03*
Y1556753D03*
X1606087Y1561653D03*
Y1559553D03*
X1610261Y1554653D03*
Y1556753D03*
X1610812Y1561653D03*
Y1559553D03*
X1614463Y1640286D03*
X1610863D03*
X1614463Y1642386D03*
X1610863D03*
X1629709Y1561653D03*
Y1559553D03*
X1620261Y1561653D03*
Y1559553D03*
X1619710Y1554653D03*
Y1556753D03*
X1624985Y1561653D03*
Y1559553D03*
X1624434Y1554653D03*
Y1556753D03*
X1629158Y1554653D03*
Y1556753D03*
X1626523Y1640286D03*
X1622923D03*
X1626523Y1642386D03*
X1622923D03*
X1638607Y1554653D03*
Y1556753D03*
X1639158Y1561653D03*
Y1559553D03*
X1643883Y1561653D03*
Y1559553D03*
X1643332Y1554653D03*
Y1556753D03*
X1634434Y1561653D03*
Y1559553D03*
X1633883Y1554653D03*
Y1556753D03*
X1633933Y1570963D03*
Y1573063D03*
X1647043Y1640286D03*
X1638583D03*
X1634983D03*
X1647043Y1642386D03*
X1638583D03*
X1634983D03*
X1657836Y1547053D03*
Y1544953D03*
X1657505Y1554653D03*
Y1556753D03*
X1658056Y1561653D03*
Y1559553D03*
X1648607Y1561653D03*
Y1559553D03*
X1652781Y1554653D03*
Y1556753D03*
X1662250Y1554653D03*
Y1556753D03*
X1648056Y1554653D03*
Y1556753D03*
X1653332Y1561653D03*
Y1559553D03*
X1650643Y1640286D03*
Y1642386D03*
X1671986Y1678943D03*
Y1681043D03*
X1671906Y1686556D03*
Y1684456D03*
G54D56*
X388273Y-14855D03*
Y-12887D03*
X728493Y-14855D03*
Y-12887D03*
X839752Y-29027D03*
Y-30995D03*
Y-9027D03*
Y-10995D03*
Y10973D03*
Y9005D03*
X1179972Y-30995D03*
Y-29027D03*
Y-10995D03*
Y-9027D03*
Y9005D03*
Y10973D03*
X1243272Y-29027D03*
Y-30995D03*
Y-9027D03*
Y-10995D03*
Y10973D03*
Y9005D03*
X1438831Y-30995D03*
Y-29027D03*
Y-10995D03*
Y-9027D03*
Y9005D03*
Y10973D03*
X1536566Y-33228D03*
Y-35196D03*
X1732125D03*
Y-33228D03*
G54D83*
X690878Y1631636D03*
Y1634195D03*
Y1629077D03*
X698358Y1631636D03*
Y1634195D03*
Y1629077D03*
X731240Y565941D03*
Y568500D03*
X723760D03*
Y565941D03*
X731240Y571059D03*
X723760D03*
G54D57*
X403312Y1000704D03*
X447400Y968982D03*
X1379498Y1000714D03*
X1423542Y968981D03*
G54D66*
X433030Y981272D03*
X1408936D03*
G54D93*
X769895Y284264D03*
Y281705D03*
Y279146D03*
Y276587D03*
Y274028D03*
Y271469D03*
X764977Y298790D03*
Y296231D03*
X769895Y286823D03*
X764977Y311585D03*
Y309026D03*
Y306467D03*
Y303908D03*
Y301349D03*
X792895Y271469D03*
Y274028D03*
Y276587D03*
Y279146D03*
Y281705D03*
Y284264D03*
X787977Y296231D03*
Y298790D03*
X792895Y286823D03*
X787977Y301349D03*
Y303908D03*
Y306467D03*
Y309026D03*
Y311585D03*
X812499Y299070D03*
Y296511D03*
Y311865D03*
Y309306D03*
Y306747D03*
Y304188D03*
Y301629D03*
X818575Y268624D03*
Y266065D03*
Y281419D03*
Y278860D03*
Y276301D03*
Y273742D03*
Y271183D03*
X841575Y266065D03*
Y268624D03*
Y271183D03*
Y273742D03*
Y276301D03*
Y278860D03*
Y281419D03*
X835499Y296511D03*
Y299070D03*
Y301629D03*
Y304188D03*
Y306747D03*
Y309306D03*
Y311865D03*
G54D84*
X693193Y1651089D03*
Y1648530D03*
Y1645970D03*
Y1643411D03*
X710771Y1648530D03*
Y1645970D03*
Y1643411D03*
Y1651089D03*
G54D48*
X282204Y1548199D03*
X288004D03*
D03*
X293804D03*
X424115D03*
X418315D03*
X424115D03*
X429915D03*
X498356Y123068D03*
X504156D03*
X546377Y1548199D03*
X552177D03*
D03*
X557977D03*
X666870Y197272D03*
X672670D03*
X835765Y1276623D03*
X841565D03*
X955900Y1292000D03*
X950100D03*
X1290077Y1581199D03*
X1295877D03*
D03*
X1301677D03*
X1431989D03*
X1437789D03*
X1426189D03*
X1431989D03*
X1554251D03*
X1560051D03*
D03*
X1565851D03*
G54D75*
X632848Y1640767D03*
X627808D03*
X632848Y1646673D03*
X627808D03*
X914243Y981428D03*
Y975522D03*
X919283D03*
Y981428D03*
X1172934Y1671413D03*
X1177974D03*
X1172934Y1677319D03*
X1177974D03*
X1658515Y1677228D03*
Y1683134D03*
X1663555Y1677228D03*
Y1683134D03*
G54D39*
X194084Y1500445D03*
X219280D03*
X231370D03*
X256566D03*
X322146D03*
X347342D03*
X359432D03*
X384628D03*
X458257D03*
X483453D03*
X495543D03*
X520739D03*
X586319D03*
X611515D03*
X623605D03*
X648801D03*
X1201957Y1533445D03*
X1227153D03*
X1239243D03*
X1264439D03*
X1330019D03*
X1355215D03*
X1367305D03*
X1392501D03*
X1466131D03*
X1491327D03*
X1503417D03*
X1528613D03*
X1594193D03*
X1619389D03*
X1631479D03*
X1656675D03*
G54D67*
X441043Y1698268D03*
X1416437D03*
G54D85*
X690500Y1671063D03*
X694240Y1678937D03*
X686760D03*
X1443487Y568881D03*
X1450967D03*
X1447227Y576755D03*
G54D76*
X632848Y1644704D03*
X627808D03*
X632848Y1642736D03*
X627808D03*
X914243Y977491D03*
Y979459D03*
X919283Y977491D03*
Y979459D03*
X1172934Y1673382D03*
X1177974D03*
X1172934Y1675350D03*
X1177974D03*
X1658515Y1679197D03*
Y1681165D03*
X1663555Y1679197D03*
Y1681165D03*
G54D58*
X401679Y991763D03*
X493229Y1057203D03*
X1377995Y991723D03*
X1469435Y1057203D03*
G54D49*
X326731Y653394D03*
X363731D03*
X433624Y594259D03*
X754645Y1426892D03*
X1166535Y1412479D03*
X1291146Y1375715D03*
X1320516D03*
X1415690Y601230D03*
X1487677Y640145D03*
X1524437Y640365D03*
X1701285Y198612D03*
X1700840Y1424519D03*
X1731660Y198612D03*
X1770442Y284934D03*
X1800002D03*
G54D94*
X766889Y1486756D03*
Y1530256D03*
G54D95*
X791280Y1704890D03*
X1066280D03*
G54D77*
X659868Y1669753D03*
X666482D03*
X942951Y933979D03*
X936337D03*
G54D86*
X705366Y1669626D03*
X701626D03*
Y1679940D03*
X705366D03*
X709106Y1669626D03*
Y1679940D03*
G54D68*
X514398Y193318D03*
Y196468D03*
Y199618D03*
Y196468D03*
X608572Y35750D03*
Y32600D03*
Y35750D03*
Y38900D03*
X628408Y762004D03*
D03*
Y758854D03*
Y765154D03*
X634946Y761053D03*
D03*
Y757903D03*
Y764203D03*
X912500Y956075D03*
X907500D03*
X912500Y952925D03*
Y956075D03*
X907500Y952925D03*
Y956075D03*
X912500Y959225D03*
X907500D03*
X923500Y948075D03*
Y951225D03*
X928500Y948075D03*
Y951225D03*
Y948075D03*
Y944925D03*
X923500Y948075D03*
Y944925D03*
X1242461Y160385D03*
Y157235D03*
Y160385D03*
Y163535D03*
X1282028Y134848D03*
Y131698D03*
Y134848D03*
Y137998D03*
X1497177Y805913D03*
Y812213D03*
Y809063D03*
D03*
X1508177Y805913D03*
Y812213D03*
Y809063D03*
D03*
G54D59*
X403163Y994332D03*
X494713Y1059772D03*
X1379479Y994292D03*
X1470919Y1059772D03*
G54D87*
X716269Y448279D03*
X719419D03*
X716269Y452844D03*
X719419D03*
X716269Y457649D03*
X719419D03*
X735086Y441981D03*
Y452844D03*
X738236Y441981D03*
Y452844D03*
G54D69*
X535382Y772864D03*
X576559Y745141D03*
G54D78*
X660222Y1667233D03*
Y1672273D03*
X666128Y1667233D03*
Y1672273D03*
X942597Y936499D03*
X936691D03*
Y931459D03*
X942597D03*
G54D96*
X793879Y194881D03*
X789942Y204724D03*
X793879Y214567D03*
X805690Y188976D03*
Y220472D03*
X817501Y194881D03*
X821438Y204724D03*
X817501Y214567D03*
X1045848Y194881D03*
X1041911Y204724D03*
X1045848Y214567D03*
X1057659Y188976D03*
Y220472D03*
X1069470Y194881D03*
X1073407Y204724D03*
X1069470Y214567D03*
X1207600Y1394000D03*
X1665904Y1949823D03*
G54D88*
X722642Y438831D03*
Y441981D03*
X719418Y438831D03*
Y441981D03*
X725718Y438831D03*
Y441981D03*
X730152Y457649D03*
Y460799D03*
X725718Y457649D03*
Y460799D03*
G54D97*
X805690Y204724D03*
X1057659D03*
G54D79*
X662191Y1667233D03*
Y1672273D03*
X664159Y1667233D03*
Y1672273D03*
X938660Y936499D03*
X940628D03*
X938660Y931459D03*
X940628D03*
G54D98*
X788941Y549260D03*
X791500D03*
X794059D03*
Y556740D03*
X791500D03*
X788941D03*
G54D89*
X722569Y463948D03*
X719419D03*
X722568Y452844D03*
X725718D03*
X744536Y448279D03*
X741386D03*
X744536Y457649D03*
X741386D03*
X744536Y452844D03*
X741386D03*
G54D99*
X828390Y1420331D03*
X841240Y1407481D03*
X832154Y1411245D03*
Y1429417D03*
X841240Y1433181D03*
X850326Y1411245D03*
Y1429417D03*
X854090Y1420331D03*
X916546Y309460D03*
X911495Y321654D03*
X916546Y333848D03*
X928740Y304409D03*
Y338899D03*
X940934Y309460D03*
X945985Y321654D03*
X940934Y333848D03*
X1007154Y1411245D03*
X1003390Y1420331D03*
X1007154Y1429417D03*
X1016240Y1407481D03*
Y1433181D03*
X1025326Y1411245D03*
Y1429417D03*
X1029090Y1420331D03*
M02*
